G04 ================== begin FILE IDENTIFICATION RECORD ==================*
G04 Layout Name:  15968-1a.brd*
G04 Film Name:    DRILL*
G04 File Format:  Gerber RS274X*
G04 File Origin:  Cadence Allegro 16.5-S058*
G04 Origin Date:  Fri Oct 14 10:23:28 2016*
G04 *
G04 Layer:  MANUFACTURING/NCLEGEND-1-6*
G04 Layer:  MANUFACTURING/DRILL SIZE*
G04 Layer:  DRAWING FORMAT/LAYER_PCB_STORY*
G04 Layer:  DRAWING FORMAT/LAYER_DRILL*
G04 Layer:  BOARD GEOMETRY/PANEL_OUTLINE*
G04 *
G04 Offset:    (0.00 0.00)*
G04 Mirror:    No*
G04 Mode:      Positive*
G04 Rotation:  0*
G04 FullContactRelief:  No*
G04 UndefLineWidth:     6.00*
G04 ================== end FILE IDENTIFICATION RECORD ====================*
%FSLAX35Y35*MOIN*%
%IR0*IPPOS*OFA0.00000B0.00000*MIA0B0*SFA1.00000B1.00000*%
%AMMACRO13*
1,1,.006,.005,0.0*
20,1,.006,.005,0.0,-.005,0.0,0.0*
1,1,.006,-.005,0.0*
1,1,.006,0.0,.005*
20,1,.006,0.0,.005,0.0,-.005,0.0*
1,1,.006,0.0,-.005*
1,1,.006,.0025,0.0*
20,1,.006,.0025,0.0,.0025,.005,0.0*
1,1,.006,.0025,.005*
20,1,.006,.0025,.005,.0015,.004,0.0*
1,1,.006,.0015,.004*
1,1,.006,.0015,0.0*
20,1,.006,.0015,0.0,.0035,0.0,0.0*
1,1,.006,.0035,0.0*
%
%ADD13MACRO13*%
%AMMACRO11*
1,1,.006,.006,.006*
20,1,.006,.006,.006,.006,-.006,0.0*
1,1,.006,.006,-.006*
20,1,.006,.006,-.006,-.006,-.006,0.0*
1,1,.006,-.006,-.006*
20,1,.006,-.006,-.006,-.006,.006,0.0*
1,1,.006,-.006,.006*
20,1,.006,-.006,.006,.006,.006,0.0*
1,1,.006,.006,.006*
1,1,.006,-.0019,.002*
20,1,.006,-.0019,.002,-.0013,.0026,0.0*
1,1,.006,-.0013,.0026*
20,1,.006,-.0013,.0026,-.0006,.0029,0.0*
1,1,.006,-.0006,.0029*
20,1,.006,-.0006,.0029,.0002,.003,0.0*
1,1,.006,.0002,.003*
20,1,.006,.0002,.003,.0012,.0028,0.0*
1,1,.006,.0012,.0028*
20,1,.006,.0012,.0028,.0019,.0023,0.0*
1,1,.006,.0019,.0023*
20,1,.006,.0019,.0023,.0021,.0017,0.0*
1,1,.006,.0021,.0017*
20,1,.006,.0021,.0017,.002,.0011,0.0*
1,1,.006,.002,.0011*
20,1,.006,.002,.0011,.0016,.0006,0.0*
1,1,.006,.0016,.0006*
20,1,.006,.0016,.0006,-.0004,-.0004,0.0*
1,1,.006,-.0004,-.0004*
20,1,.006,-.0004,-.0004,-.0013,-.0011,0.0*
1,1,.006,-.0013,-.0011*
20,1,.006,-.0013,-.0011,-.0019,-.0021,0.0*
1,1,.006,-.0019,-.0021*
20,1,.006,-.0019,-.0021,-.0021,-.003,0.0*
1,1,.006,-.0021,-.003*
20,1,.006,-.0021,-.003,.0021,-.003,0.0*
1,1,.006,.0021,-.003*
%
%ADD11MACRO11*%
%AMMACRO12*
1,1,.006,.028788,-.0695*
20,1,.006,.028788,-.0695,-.028788,-.0695,0.0*
1,1,.006,-.028788,-.0695*
20,1,.006,-.028788,-.0695,-.0695,-.028788,0.0*
1,1,.006,-.0695,-.028788*
20,1,.006,-.0695,-.028788,-.0695,.028788,0.0*
1,1,.006,-.0695,.028788*
20,1,.006,-.0695,.028788,-.028788,.0695,0.0*
1,1,.006,-.028788,.0695*
20,1,.006,-.028788,.0695,.028788,.0695,0.0*
1,1,.006,.028788,.0695*
20,1,.006,.028788,.0695,.0695,.028788,0.0*
1,1,.006,.0695,.028788*
20,1,.006,.0695,.028788,.0695,-.028788,0.0*
1,1,.006,.0695,-.028788*
20,1,.006,.0695,-.028788,.028788,-.0695,0.0*
1,1,.006,.028788,-.0695*
1,1,.006,-.02548,-.02433*
20,1,.006,-.02548,-.02433,-.01853,-.03012,0.0*
1,1,.006,-.01853,-.03012*
20,1,.006,-.01853,-.03012,-.01043,-.03359,0.0*
1,1,.006,-.01043,-.03359*
20,1,.006,-.01043,-.03359,0.0,-.03475,0.0*
1,1,.006,0.0,-.03475*
20,1,.006,0.0,-.03475,.01043,-.03243,0.0*
1,1,.006,.01043,-.03243*
20,1,.006,.01043,-.03243,.01853,-.0278,0.0*
1,1,.006,.01853,-.0278*
20,1,.006,.01853,-.0278,.02433,-.01969,0.0*
1,1,.006,.02433,-.01969*
20,1,.006,.02433,-.01969,.02548,-.01043,0.0*
1,1,.006,.02548,-.01043*
20,1,.006,.02548,-.01043,.02317,-.00116,0.0*
1,1,.006,.02317,-.00116*
20,1,.006,.02317,-.00116,.01737,.00463,0.0*
1,1,.006,.01737,.00463*
20,1,.006,.01737,.00463,.00927,.00927,0.0*
1,1,.006,.00927,.00927*
20,1,.006,.00927,.00927,.00116,.01042,0.0*
1,1,.006,.00116,.01042*
20,1,.006,.00116,.01042,-.00695,.00927,0.0*
1,1,.006,-.00695,.00927*
20,1,.006,-.00695,.00927,-.01737,.00463,0.0*
1,1,.006,-.01737,.00463*
20,1,.006,-.01737,.00463,-.0139,.03475,0.0*
1,1,.006,-.0139,.03475*
20,1,.006,-.0139,.03475,.01737,.03475,0.0*
1,1,.006,.01737,.03475*
%
%ADD12MACRO12*%
%AMMACRO10*
1,1,.006,.043,0.0*
20,1,.006,.043,0.0,0.0,-.043,0.0*
1,1,.006,0.0,-.043*
20,1,.006,0.0,-.043,-.043,0.0,0.0*
1,1,.006,-.043,0.0*
20,1,.006,-.043,0.0,0.0,.043,0.0*
1,1,.006,0.0,.043*
20,1,.006,0.0,.043,.043,0.0,0.0*
1,1,.006,.043,0.0*
1,1,.006,-.01362,-.00358*
20,1,.006,-.01362,-.00358,-.0086,.00143,0.0*
1,1,.006,-.0086,.00143*
20,1,.006,-.0086,.00143,-.0043,.0043,0.0*
1,1,.006,-.0043,.0043*
20,1,.006,-.0043,.0043,.00143,.00573,0.0*
1,1,.006,.00143,.00573*
20,1,.006,.00143,.00573,.00645,.0043,0.0*
1,1,.006,.00645,.0043*
20,1,.006,.00645,.0043,.01003,.00143,0.0*
1,1,.006,.01003,.00143*
20,1,.006,.01003,.00143,.0129,-.00287,0.0*
1,1,.006,.0129,-.00287*
20,1,.006,.0129,-.00287,.01362,-.00788,0.0*
1,1,.006,.01362,-.00788*
20,1,.006,.01362,-.00788,.0129,-.01218,0.0*
1,1,.006,.0129,-.01218*
20,1,.006,.0129,-.01218,.01003,-.01648,0.0*
1,1,.006,.01003,-.01648*
20,1,.006,.01003,-.01648,.00573,-.02007,0.0*
1,1,.006,.00573,-.02007*
20,1,.006,.00573,-.02007,.00072,-.0215,0.0*
1,1,.006,.00072,-.0215*
20,1,.006,.00072,-.0215,-.00502,-.02007,0.0*
1,1,.006,-.00502,-.02007*
20,1,.006,-.00502,-.02007,-.01003,-.01577,0.0*
1,1,.006,-.01003,-.01577*
20,1,.006,-.01003,-.01577,-.0129,-.00932,0.0*
1,1,.006,-.0129,-.00932*
20,1,.006,-.0129,-.00932,-.01362,-.00215,0.0*
1,1,.006,-.01362,-.00215*
20,1,.006,-.01362,-.00215,-.01218,.00717,0.0*
1,1,.006,-.01218,.00717*
20,1,.006,-.01218,.00717,-.01003,.01218,0.0*
1,1,.006,-.01003,.01218*
20,1,.006,-.01003,.01218,-.00645,.0172,0.0*
1,1,.006,-.00645,.0172*
20,1,.006,-.00645,.0172,-.00143,.02078,0.0*
1,1,.006,-.00143,.02078*
20,1,.006,-.00143,.02078,.00358,.0215,0.0*
1,1,.006,.00358,.0215*
20,1,.006,.00358,.0215,.0086,.02007,0.0*
1,1,.006,.0086,.02007*
20,1,.006,.0086,.02007,.01218,.01648,0.0*
1,1,.006,.01218,.01648*
%
%ADD10MACRO10*%
%AMMACRO16*
1,1,.006,0.0,.0355*
20,1,.006,0.0,.0355,-.030744,.01775,0.0*
1,1,.006,-.030744,.01775*
20,1,.006,-.030744,.01775,-.030744,-.01775,0.0*
1,1,.006,-.030744,-.01775*
20,1,.006,-.030744,-.01775,0.0,-.0355,0.0*
1,1,.006,0.0,-.0355*
20,1,.006,0.0,-.0355,.030744,-.01775,0.0*
1,1,.006,.030744,-.01775*
20,1,.006,.030744,-.01775,.030744,.01775,0.0*
1,1,.006,.030744,.01775*
20,1,.006,.030744,.01775,0.0,.0355,0.0*
1,1,.006,0.0,.0355*
1,1,.006,.0071,-.01775*
20,1,.006,.0071,-.01775,.0071,.01775,0.0*
1,1,.006,.0071,.01775*
20,1,.006,.0071,.01775,-.01479,-.00769,0.0*
1,1,.006,-.01479,-.00769*
20,1,.006,-.01479,-.00769,.01479,-.00769,0.0*
1,1,.006,.01479,-.00769*
%
%ADD16MACRO16*%
%AMMACRO15*
1,1,.006,.014,0.0*
20,1,.006,.014,0.0,.007,.012124,0.0*
1,1,.006,.007,.012124*
20,1,.006,.007,.012124,-.007,.012124,0.0*
1,1,.006,-.007,.012124*
20,1,.006,-.007,.012124,-.014,0.0,0.0*
1,1,.006,-.014,0.0*
20,1,.006,-.014,0.0,-.007,-.012124,0.0*
1,1,.006,-.007,-.012124*
20,1,.006,-.007,-.012124,.007,-.012124,0.0*
1,1,.006,.007,-.012124*
20,1,.006,.007,-.012124,.014,0.0,0.0*
1,1,.006,.014,0.0*
1,1,.006,-.00513,-.0042*
20,1,.006,-.00513,-.0042,-.00373,-.00583,0.0*
1,1,.006,-.00373,-.00583*
20,1,.006,-.00373,-.00583,-.00187,-.00677,0.0*
1,1,.006,-.00187,-.00677*
20,1,.006,-.00187,-.00677,.00023,-.007,0.0*
1,1,.006,.00023,-.007*
20,1,.006,.00023,-.007,.0021,-.00677,0.0*
1,1,.006,.0021,-.00677*
20,1,.006,.0021,-.00677,.00397,-.0056,0.0*
1,1,.006,.00397,-.0056*
20,1,.006,.00397,-.0056,.00513,-.0042,0.0*
1,1,.006,.00513,-.0042*
20,1,.006,.00513,-.0042,.00537,-.0028,0.0*
1,1,.006,.00537,-.0028*
20,1,.006,.00537,-.0028,.0049,-.00117,0.0*
1,1,.006,.0049,-.00117*
20,1,.006,.0049,-.00117,.00327,0.0,0.0*
1,1,.006,.00327,0.0*
20,1,.006,.00327,0.0,.00163,.00047,0.0*
1,1,.006,.00163,.00047*
20,1,.006,.00163,.00047,-.00047,.00047,0.0*
1,1,.006,-.00047,.00047*
1,1,.006,.00163,.00047*
20,1,.006,.00163,.00047,.00303,.00117,0.0*
1,1,.006,.00303,.00117*
20,1,.006,.00303,.00117,.0042,.00233,0.0*
1,1,.006,.0042,.00233*
20,1,.006,.0042,.00233,.00467,.00373,0.0*
1,1,.006,.00467,.00373*
20,1,.006,.00467,.00373,.0042,.00513,0.0*
1,1,.006,.0042,.00513*
20,1,.006,.0042,.00513,.00303,.0063,0.0*
1,1,.006,.00303,.0063*
20,1,.006,.00303,.0063,.00093,.007,0.0*
1,1,.006,.00093,.007*
20,1,.006,.00093,.007,-.00117,.00677,0.0*
1,1,.006,-.00117,.00677*
20,1,.006,-.00117,.00677,-.00327,.00583,0.0*
1,1,.006,-.00327,.00583*
%
%ADD15MACRO15*%
%AMMACRO14*
1,1,.006,0.0,.0465*
20,1,.006,0.0,.0465,.0465,-.0465,0.0*
1,1,.006,.0465,-.0465*
20,1,.006,.0465,-.0465,-.0465,-.0465,0.0*
1,1,.006,-.0465,-.0465*
20,1,.006,-.0465,-.0465,0.0,.0465,0.0*
1,1,.006,0.0,.0465*
1,1,.006,-.00155,-.02325*
20,1,.006,-.00155,-.02325,0.0,-.01318,0.0*
1,1,.006,0.0,-.01318*
20,1,.006,0.0,-.01318,.00233,-.00465,0.0*
1,1,.006,.00233,-.00465*
20,1,.006,.00233,-.00465,.00542,.0031,0.0*
1,1,.006,.00542,.0031*
20,1,.006,.00542,.0031,.0093,.01162,0.0*
1,1,.006,.0093,.01162*
20,1,.006,.0093,.01162,.0155,.02325,0.0*
1,1,.006,.0155,.02325*
20,1,.006,.0155,.02325,-.0155,.02325,0.0*
1,1,.006,-.0155,.02325*
%
%ADD14MACRO14*%
%ADD17C,.02*%
%ADD18C,.005*%
%ADD19C,.006*%
G75*
%LPD*%
G75*
G54D10*
X21800Y-41500D03*
X14794Y226306D03*
X542107Y17432D03*
X585785Y228866D03*
X610300Y-43600D03*
X612500Y540800D03*
X704750Y70450D03*
G54D11*
X25700Y89200D03*
X27207Y85293D03*
X24400Y81900D03*
X22300Y85000D03*
X21800Y78600D03*
X21600Y74000D03*
X28200Y160400D03*
X95906Y-53300D03*
X84619Y-27663D03*
X89467Y-47981D03*
X84671Y-44973D03*
X79444Y-46817D03*
X90546Y-41425D03*
X90332Y-30191D03*
X85442Y-39927D03*
X79444Y-41282D03*
X90400Y-36500D03*
X85231Y-34026D03*
X79035Y-30696D03*
X79103Y-35748D03*
X107800Y4300D03*
X107000Y-49000D03*
X106800Y-53000D03*
X107100Y-36900D03*
X107500Y-33200D03*
X76300Y79700D03*
X78900Y82400D03*
X78200Y76200D03*
X78300Y72600D03*
X78400Y68900D03*
X74700Y73100D03*
X73500Y76600D03*
X74900Y65800D03*
X74800Y69500D03*
X71000Y73500D03*
X67400Y76200D03*
X71100Y69800D03*
X67200Y72400D03*
Y68800D03*
X83400Y55300D03*
X72400Y22300D03*
X90100Y23100D03*
X64200Y99200D03*
X78000Y99900D03*
X87300Y55300D03*
X75500Y55400D03*
X79099Y55280D03*
X33200Y98700D03*
X30600Y88100D03*
X33700Y91400D03*
X29400Y92300D03*
X32800Y95000D03*
X102000Y40300D03*
X103000Y28300D03*
X105800Y40200D03*
X107000Y28300D03*
X96000Y80100D03*
X97800Y76800D03*
X93000Y73300D03*
X93800Y77000D03*
X89800Y76700D03*
X50700Y81900D03*
X58000Y81600D03*
X53000Y59800D03*
X49400Y60000D03*
X54300Y81700D03*
X71500Y39500D03*
X71700Y31500D03*
X69300Y36500D03*
X69400Y26700D03*
X86000Y36087D03*
X78600Y36200D03*
X74600Y36100D03*
X82300Y36200D03*
X64600Y104500D03*
X78000Y105800D03*
X32400Y160600D03*
X29200Y164000D03*
X33100Y164800D03*
X36000Y161800D03*
X31000Y156900D03*
X55600Y105100D03*
X54400Y110000D03*
X54600Y114900D03*
X59000Y107900D03*
X59700Y115200D03*
X44200Y212200D03*
X39200Y212100D03*
X44400Y217400D03*
X39300D03*
X111600Y4100D03*
X115500Y4000D03*
X119300Y3800D03*
X123000D03*
X127000Y3900D03*
X130800Y4000D03*
X111300Y-49100D03*
X111100Y-53100D03*
X111400Y-37000D03*
X111800Y-33300D03*
X131266Y85081D03*
X135025Y85092D03*
X138722Y85144D03*
X131666Y78581D03*
X135425Y78592D03*
X139122Y78644D03*
X109600Y40000D03*
X110800Y28100D03*
X138922Y94844D03*
X135225Y94792D03*
X131466Y94781D03*
X172300Y94300D03*
X169800Y91100D03*
X174900Y90900D03*
X152700Y33300D03*
X152279Y36876D03*
X153000Y40700D03*
X167100Y181200D03*
X163300Y178900D03*
X135100Y161900D03*
X155600Y166300D03*
X151700D03*
X134900Y165700D03*
X146165Y120044D03*
X140552Y117907D03*
X136626Y118116D03*
X158100Y116300D03*
X158000Y120900D03*
Y124800D03*
X142500Y203900D03*
X145300Y201100D03*
X148314Y203751D03*
X162100Y193800D03*
X165700Y195000D03*
X363700Y78200D03*
X421405Y90902D03*
X418437Y87727D03*
X423690Y87875D03*
X428500Y107700D03*
X424200Y103800D03*
X453500Y-9800D03*
X449900Y-9700D03*
X453400Y-13500D03*
X449800D03*
X453500Y-5700D03*
X449900D03*
X453600Y-2000D03*
X450000Y-1900D03*
X460535Y76560D03*
X456662Y76376D03*
X432100Y103800D03*
X495500Y219600D03*
Y210500D03*
X495400Y215300D03*
X500200Y219500D03*
X504800Y219600D03*
X504500Y210600D03*
X500200Y210400D03*
X504700Y215300D03*
X500100Y215200D03*
X540500Y219500D03*
X532200Y219300D03*
X527000Y219500D03*
X519900D03*
X704750Y182850D03*
G54D12*
X15748Y128150D03*
X542913D03*
X704750Y98550D03*
G54D13*
X6487Y175762D03*
Y165762D03*
X14947Y175971D03*
Y165971D03*
X22700Y190800D03*
X26300D03*
X26600Y201000D03*
X23000D03*
X6487Y235762D03*
X25453Y235870D03*
X15453D03*
X6487Y225762D03*
Y215762D03*
Y205762D03*
Y195762D03*
Y185762D03*
X14947Y195971D03*
Y185971D03*
X92940Y6625D03*
X99000Y13800D03*
X99200Y18100D03*
X107400Y11300D03*
X98200Y10000D03*
X94042Y9842D03*
X93900Y95300D03*
X104600Y95000D03*
X102400Y92600D03*
X106800Y92700D03*
X104600Y90500D03*
X45800Y54800D03*
X45200Y89400D03*
X30700Y56400D03*
X98300Y72000D03*
X39900Y72800D03*
X87900Y94500D03*
X87250Y100650D03*
X98300Y67500D03*
X104500Y56200D03*
X88000Y65200D03*
X83200Y60000D03*
X48800Y87100D03*
X62000Y142900D03*
X56300Y180000D03*
X101500Y135908D03*
X62700Y150100D03*
X69000Y143300D03*
X79000Y142500D03*
X77000Y140300D03*
X81300Y140400D03*
X79200Y138100D03*
X104743Y174953D03*
X98900Y126800D03*
X85700Y129900D03*
X85900Y126300D03*
X81700Y129700D03*
X81800Y125900D03*
X68800Y139000D03*
X59400Y151000D03*
X56400Y164250D03*
X67750Y160700D03*
X66100Y151000D03*
X98900Y172350D03*
X92400Y163100D03*
X80000Y158900D03*
X80400Y167200D03*
X102202Y131798D03*
X101500Y139900D03*
X100000Y175700D03*
X105500Y109500D03*
X105400Y153600D03*
X106500Y149000D03*
X105218Y137218D03*
X71500Y168500D03*
X100800Y189700D03*
X100700Y182900D03*
X98400Y233100D03*
X59600Y214000D03*
X100700Y186300D03*
X35453Y235870D03*
X45453D03*
X55453D03*
X65453D03*
X75453D03*
X84400Y232900D03*
X89600D03*
X94900Y233000D03*
X56500Y202900D03*
X100500Y209300D03*
X75591Y202676D03*
X79843D03*
X83500Y189000D03*
X96000Y192000D03*
X72200Y202400D03*
X67500Y213500D03*
X64000D03*
X161100Y13600D03*
X126800Y-53409D03*
X135182D03*
X144631D03*
X154080D03*
X163529D03*
X172977D03*
X116900Y-35400D03*
X121801Y16999D03*
X146600Y3400D03*
X159450Y8750D03*
X160400Y4900D03*
X111018Y11382D03*
X148300Y16700D03*
X147878Y13326D03*
X182000Y66700D03*
X174400Y32500D03*
X176300Y45200D03*
X159450Y97400D03*
X151150Y83500D03*
X124900Y88900D03*
X161800Y71100D03*
X117200Y65750D03*
X116900Y59450D03*
X134000Y63400D03*
X151550Y87500D03*
X132600Y39900D03*
X147900Y73800D03*
X153300Y22300D03*
X137400Y61900D03*
X125000Y93400D03*
X129400Y62200D03*
X169800Y39200D03*
X161400Y58700D03*
X154300Y56400D03*
X124100Y78900D03*
X137900Y49400D03*
X110781Y87200D03*
X111750Y98450D03*
X152900Y46500D03*
X114850Y95650D03*
X181700Y72700D03*
X161694Y55106D03*
X154300Y49600D03*
X156600Y109800D03*
X152650D03*
X148950Y109600D03*
X116100Y169700D03*
X120400Y169800D03*
X125300Y170200D03*
X111800Y113700D03*
X117600Y117700D03*
X116176Y156724D03*
X109500Y168752D03*
X180076Y179876D03*
X175600Y166800D03*
X121700Y117300D03*
X111924Y156724D03*
X109500Y164500D03*
X172000Y166800D03*
X124400Y103100D03*
X181400Y124500D03*
X172300Y192800D03*
X164200Y205100D03*
X180300Y187200D03*
X179900Y191300D03*
X180000Y198500D03*
Y183500D03*
X183683Y198517D03*
X173300Y204969D03*
X240100Y20900D03*
X221900Y5100D03*
X235600Y5300D03*
X247200Y5400D03*
X195200Y5700D03*
X191875Y-53409D03*
X201324D03*
X210773D03*
X220221D03*
X229670D03*
X239119D03*
X248568D03*
X258017D03*
X267466D03*
X252300Y22200D03*
X255900Y35000D03*
X246500Y47900D03*
X200500Y31500D03*
X216300Y46700D03*
X226600Y21400D03*
X198300Y73200D03*
X196400Y91600D03*
X193900Y51600D03*
X202800Y50200D03*
X218900Y65600D03*
X198900Y21200D03*
X230300Y45100D03*
X233800Y66000D03*
X199400Y81400D03*
X236900Y85800D03*
X233700Y54400D03*
X262400Y169900D03*
X202300Y165100D03*
X196850Y177950D03*
X246800Y112500D03*
X198300Y111700D03*
X188900Y173300D03*
X225100Y168100D03*
X199900Y161600D03*
X192200Y166700D03*
X195900Y162100D03*
X242800Y200600D03*
X243000Y185300D03*
X239400Y191500D03*
X191600Y185600D03*
X209400Y200100D03*
X225600Y185900D03*
X230500Y191400D03*
X224100Y200100D03*
X256747Y199700D03*
X250100Y193000D03*
X267500Y182000D03*
X266000Y185100D03*
X254900Y188300D03*
X345042Y-41479D03*
X339942D03*
X324642D03*
X334842D03*
X329742D03*
X319070Y-41541D03*
X276914Y-53409D03*
X286363D03*
X295812D03*
X305261D03*
X314710D03*
X324158D03*
X333607D03*
X343056D03*
X324021Y-46464D03*
X334221D03*
X344421D03*
X320021D03*
X330221D03*
X340421D03*
X329242Y-36479D03*
X339442D03*
X325242D03*
X335442D03*
X345642D03*
X328000Y30500D03*
Y59000D03*
X339649Y41539D03*
X329400Y50300D03*
X339100Y73300D03*
X324600Y36900D03*
X343524Y36971D03*
X346000Y34640D03*
X300800Y100100D03*
X337900Y46800D03*
X346150Y84800D03*
X328655Y170950D03*
X313400Y119100D03*
X289600Y162100D03*
X308600Y171100D03*
X274400Y161700D03*
X327200Y178276D03*
Y174024D03*
X348200Y169900D03*
X326600Y182000D03*
X295800Y195900D03*
X294600Y201300D03*
X301500Y186300D03*
X332000Y192200D03*
X329400Y195900D03*
X334794Y195294D03*
X321600Y186300D03*
X323243Y183323D03*
X396042Y-41479D03*
X390942D03*
X380742D03*
X385842D03*
X375642D03*
X370542D03*
X365442D03*
X360342D03*
X355242D03*
X401142D03*
X350142D03*
X423852Y4375D03*
X420252Y-36925D03*
X410052Y-36825D03*
X380500Y17100D03*
X352505Y-53409D03*
X361954D03*
X371403D03*
X380851D03*
X390300D03*
X399815Y-52741D03*
X415100Y3400D03*
X352600Y7600D03*
X380200Y6800D03*
X380500Y13200D03*
X380200Y3300D03*
X354621Y-46464D03*
X364821D03*
X375021D03*
X385221D03*
X395421D03*
X350621D03*
X360821D03*
X371021D03*
X381221D03*
X391421D03*
X349642Y-36479D03*
X359842D03*
X370042D03*
X380242D03*
X390442D03*
X400642D03*
X355842D03*
X366042D03*
X376242D03*
X386442D03*
X396642D03*
X405500Y29200D03*
X370400Y88200D03*
X377800Y87800D03*
X383300Y50700D03*
X383500Y65800D03*
X388000Y41600D03*
X394500Y34000D03*
X380300Y21600D03*
X405800Y21100D03*
Y94200D03*
X405600Y87500D03*
X420322Y56072D03*
X423202Y56119D03*
X426128Y50188D03*
Y53348D03*
X426065Y56213D03*
X426113Y59046D03*
X425971Y62050D03*
X423500Y34200D03*
X416300Y37100D03*
X418705Y34695D03*
X405569Y72731D03*
X409026Y61211D03*
X383600Y55532D03*
X401211Y46589D03*
X373300Y35400D03*
X384000Y41600D03*
X391600Y29400D03*
X361600Y69100D03*
X383500Y69200D03*
X383600Y59618D03*
X383400Y46600D03*
X362400Y34500D03*
X404500Y36300D03*
X380200Y25800D03*
X349701Y64199D03*
X353100Y63900D03*
X359023Y47177D03*
X355370Y37411D03*
X355300Y81400D03*
X349700Y56000D03*
X349000Y28300D03*
X404500Y47769D03*
X409400Y69800D03*
X423500Y37800D03*
X412000Y29900D03*
X356700Y86600D03*
X353098Y55882D03*
X350300Y31800D03*
X352138Y50729D03*
X351500Y36100D03*
X355536Y50589D03*
X352700Y40000D03*
X355399Y47191D03*
X355300Y33900D03*
X391200Y35700D03*
X398805Y66200D03*
X408600Y27376D03*
X388006Y37706D03*
X395406Y66092D03*
X418650Y22850D03*
X408600Y23124D03*
X402500Y89124D03*
X375514Y85000D03*
X402500Y93376D03*
X372114Y85000D03*
X358700Y38100D03*
X362100D03*
X372400Y41100D03*
X436752Y4175D03*
X498052Y-625D03*
X490200Y-6400D03*
X488652Y-18225D03*
X496352Y-19025D03*
X432452Y-36225D03*
X447252Y-47725D03*
X445252Y-37225D03*
X455701Y-53425D03*
X502945D03*
X493496D03*
X484047D03*
X474598D03*
X465149D03*
X446252D03*
X433900Y11000D03*
X438900Y13400D03*
X428600Y16900D03*
X469300Y87600D03*
X459652Y31575D03*
X458100Y47300D03*
Y53700D03*
X448200Y93000D03*
X448369Y86631D03*
X432091Y56151D03*
X429056Y56135D03*
X457400Y41800D03*
X468588Y55981D03*
X431382Y35283D03*
X437300Y91100D03*
X454085Y63272D03*
X452496Y70099D03*
X454500Y29300D03*
X439418Y26110D03*
X439000Y87700D03*
X451381Y88210D03*
Y91719D03*
X435287Y25646D03*
X441688Y74914D03*
X449400Y26433D03*
X454000Y40600D03*
X429850Y22950D03*
X461513Y48758D03*
Y52267D03*
X452888Y108444D03*
X457097Y108548D03*
X457245Y105151D03*
X453736D03*
X466361Y230936D03*
X467506Y226106D03*
X502000Y229400D03*
X466010Y216328D03*
X492961Y227336D03*
X480761Y227936D03*
X505961Y236936D03*
X488161Y236336D03*
X479761D03*
X499761D03*
X455700Y205800D03*
X528590Y-12237D03*
Y2763D03*
X532137Y7890D03*
X532691Y-17725D03*
X531600Y-31800D03*
X523300Y-32100D03*
X531291Y-53425D03*
X521842D03*
X512393D03*
X524994Y-38000D03*
X530994D03*
X534737Y40290D03*
X534337Y52790D03*
X534637Y74290D03*
Y92590D03*
X532778Y21738D03*
X512000Y158400D03*
X511900Y174400D03*
Y142700D03*
X521900Y179500D03*
X548200Y169900D03*
X548300Y178100D03*
X578337Y166890D03*
X577748Y181113D03*
X529000Y158500D03*
X521600Y158400D03*
X520500Y154500D03*
X525000Y158000D03*
X551376Y176271D03*
Y172019D03*
X517900Y103300D03*
X524200Y181600D03*
X519700Y181900D03*
X521900Y184000D03*
X545300Y236800D03*
X529500Y236400D03*
X519761Y236336D03*
X537200Y236400D03*
X559761Y236336D03*
X579761D03*
X577748Y211113D03*
X578337Y226890D03*
X577748Y191113D03*
Y201113D03*
X524000Y200000D03*
X520970Y192569D03*
X528500Y200000D03*
X593337Y166890D03*
Y176890D03*
X608337Y166890D03*
Y176890D03*
X599761Y236336D03*
X593337Y206890D03*
Y216890D03*
Y226890D03*
Y186890D03*
Y196890D03*
X608337Y206890D03*
Y216890D03*
Y226890D03*
Y186890D03*
Y196890D03*
X704750Y210950D03*
G54D14*
X168268Y143189D03*
Y223189D03*
X456258Y143189D03*
Y223189D03*
X704750Y42350D03*
G54D15*
X122403Y148109D03*
X126338Y155984D03*
X130278Y148109D03*
X134213Y155984D03*
X138148Y148109D03*
X142088Y155984D03*
X146023Y148109D03*
X149963Y155984D03*
X153898Y148109D03*
X157833Y155984D03*
X161773Y148109D03*
X173583Y155984D03*
X177518Y148109D03*
X181458Y155984D03*
X185393Y148109D03*
X189333Y155984D03*
X122403Y138269D03*
X126338Y130394D03*
X130278Y138269D03*
X134213Y130394D03*
X138148Y138269D03*
X142088Y130394D03*
X146023Y138269D03*
X149963Y130394D03*
X153898Y138269D03*
X157833Y130394D03*
X161773Y138269D03*
X173583Y130394D03*
X177518Y138269D03*
X181458Y130394D03*
X185393Y138269D03*
X189333Y130394D03*
X122403Y228109D03*
X126338Y235984D03*
X130278Y228109D03*
X134213Y235984D03*
X138148Y228109D03*
X142088Y235984D03*
X146023Y228109D03*
X149963Y235984D03*
X153898Y228109D03*
X157833Y235984D03*
X161773Y228109D03*
X173583Y235984D03*
X177518Y228109D03*
X181458Y235984D03*
X185393Y228109D03*
X189333Y235984D03*
X122403Y218269D03*
X126338Y210394D03*
X130278Y218269D03*
X134213Y210394D03*
X138148Y218269D03*
X142088Y210394D03*
X146023Y218269D03*
X149963Y210394D03*
X153898Y218269D03*
X157833Y210394D03*
X161773Y218269D03*
X173583Y210394D03*
X177518Y218269D03*
X181458Y210394D03*
X185393Y218269D03*
X189333Y210394D03*
X193268Y148109D03*
X197203Y155984D03*
X201143Y148109D03*
X205078Y155984D03*
X209018Y148109D03*
X212953Y155984D03*
X216888Y148109D03*
X220828Y155984D03*
X224763Y148109D03*
X228703Y155984D03*
X232638Y148109D03*
X236573Y155984D03*
X240513Y148109D03*
X244448Y155984D03*
X248388Y148109D03*
X252323Y155984D03*
X256258Y148109D03*
X260198Y155984D03*
X264133Y148109D03*
X268073Y155984D03*
X193268Y138269D03*
X197203Y130394D03*
X201143Y138269D03*
X205078Y130394D03*
X209018Y138269D03*
X212953Y130394D03*
X216888Y138269D03*
X220828Y130394D03*
X224763Y138269D03*
X228703Y130394D03*
X232638Y138269D03*
X236573Y130394D03*
X240513Y138269D03*
X244448Y130394D03*
X248388Y138269D03*
X252323Y130394D03*
X256258Y138269D03*
X260198Y130394D03*
X264133Y138269D03*
X268073Y130394D03*
X193268Y228109D03*
X197203Y235984D03*
X201143Y228109D03*
X205078Y235984D03*
X209018Y228109D03*
X212953Y235984D03*
X216888Y228109D03*
X220828Y235984D03*
X224763Y228109D03*
X228703Y235984D03*
X232638Y228109D03*
X236573Y235984D03*
X240513Y228109D03*
X244448Y235984D03*
X248388Y228109D03*
X252323Y235984D03*
X256258Y228109D03*
X260198Y235984D03*
X264133Y228109D03*
X268073Y235984D03*
X193268Y218269D03*
X197203Y210394D03*
X201143Y218269D03*
X205078Y210394D03*
X209018Y218269D03*
X212953Y210394D03*
X216888Y218269D03*
X220828Y210394D03*
X224763Y218269D03*
X228703Y210394D03*
X232638Y218269D03*
X236573Y210394D03*
X240513Y218269D03*
X244448Y210394D03*
X248388Y218269D03*
X252323Y210394D03*
X256258Y218269D03*
X260198Y210394D03*
X264133Y218269D03*
X268073Y210394D03*
X272008Y148109D03*
X275943Y155984D03*
X279883Y148109D03*
X283818Y155984D03*
X287758Y148109D03*
X291693Y155984D03*
X295628Y148109D03*
X299568Y155984D03*
X303503Y148109D03*
X307443Y155984D03*
X311378Y148109D03*
X315313Y155984D03*
X319253Y148109D03*
X323188Y155984D03*
X327128Y148109D03*
X331063Y155984D03*
X334998Y148109D03*
X338938Y155984D03*
X342873Y148109D03*
X346813Y155984D03*
X272008Y138269D03*
X275943Y130394D03*
X279883Y138269D03*
X283818Y130394D03*
X287758Y138269D03*
X291693Y130394D03*
X295628Y138269D03*
X299568Y130394D03*
X303503Y138269D03*
X307443Y130394D03*
X311378Y138269D03*
X315313Y130394D03*
X319253Y138269D03*
X323188Y130394D03*
X327128Y138269D03*
X331063Y130394D03*
X334998Y138269D03*
X338938Y130394D03*
X342873Y138269D03*
X346813Y130394D03*
X272008Y228109D03*
X275943Y235984D03*
X279883Y228109D03*
X283818Y235984D03*
X287758Y228109D03*
X291693Y235984D03*
X295628Y228109D03*
X299568Y235984D03*
X303503Y228109D03*
X307443Y235984D03*
X311378Y228109D03*
X315313Y235984D03*
X319253Y228109D03*
X323188Y235984D03*
X327128Y228109D03*
X331063Y235984D03*
X334998Y228109D03*
X338938Y235984D03*
X342873Y228109D03*
X346813Y235984D03*
X272008Y218269D03*
X275943Y210394D03*
X279883Y218269D03*
X283818Y210394D03*
X287758Y218269D03*
X291693Y210394D03*
X295628Y218269D03*
X299568Y210394D03*
X303503Y218269D03*
X307443Y210394D03*
X311378Y218269D03*
X315313Y210394D03*
X319253Y218269D03*
X323188Y210394D03*
X327128Y218269D03*
X331063Y210394D03*
X334998Y218269D03*
X338938Y210394D03*
X342873Y218269D03*
X346813Y210394D03*
X350748Y148109D03*
X354683Y155984D03*
X358623Y148109D03*
X362558Y155984D03*
X366498Y148109D03*
X370433Y155984D03*
X374368Y148109D03*
X378308Y155984D03*
X382243Y148109D03*
X386183Y155984D03*
X390118Y148109D03*
X394053Y155984D03*
X397993Y148109D03*
X401928Y155984D03*
X405868Y148109D03*
X409803Y155984D03*
X413738Y148109D03*
X417678Y155984D03*
X421613Y148109D03*
X425553Y155984D03*
X429488Y148109D03*
X350748Y138269D03*
X354683Y130394D03*
X358623Y138269D03*
X362558Y130394D03*
X366498Y138269D03*
X370433Y130394D03*
X374368Y138269D03*
X378308Y130394D03*
X382243Y138269D03*
X386183Y130394D03*
X390118Y138269D03*
X394053Y130394D03*
X397993Y138269D03*
X401928Y130394D03*
X405868Y138269D03*
X409803Y130394D03*
X413738Y138269D03*
X417678Y130394D03*
X421613Y138269D03*
X425553Y130394D03*
X429488Y138269D03*
X350748Y228109D03*
X354683Y235984D03*
X358623Y228109D03*
X362558Y235984D03*
X366498Y228109D03*
X370433Y235984D03*
X374368Y228109D03*
X378308Y235984D03*
X382243Y228109D03*
X386183Y235984D03*
X390118Y228109D03*
X394053Y235984D03*
X397993Y228109D03*
X401928Y235984D03*
X405868Y228109D03*
X409803Y235984D03*
X413738Y228109D03*
X417678Y235984D03*
X421613Y228109D03*
X425553Y235984D03*
X429488Y228109D03*
X350748Y218269D03*
X354683Y210394D03*
X358623Y218269D03*
X362558Y210394D03*
X366498Y218269D03*
X370433Y210394D03*
X374368Y218269D03*
X378308Y210394D03*
X382243Y218269D03*
X386183Y210394D03*
X390118Y218269D03*
X394053Y210394D03*
X397993Y218269D03*
X401928Y210394D03*
X405868Y218269D03*
X409803Y210394D03*
X413738Y218269D03*
X417678Y210394D03*
X421613Y218269D03*
X425553Y210394D03*
X429488Y218269D03*
X433423Y155984D03*
X437363Y148109D03*
X441298Y155984D03*
X445238Y148109D03*
X449173Y155984D03*
X433423Y130394D03*
X437363Y138269D03*
X441298Y130394D03*
X445238Y138269D03*
X449173Y130394D03*
X433423Y235984D03*
X437363Y228109D03*
X441298Y235984D03*
X445238Y228109D03*
X449173Y235984D03*
X433423Y210394D03*
X437363Y218269D03*
X441298Y210394D03*
X445238Y218269D03*
X449173Y210394D03*
X704750Y154750D03*
G54D16*
X539370Y190256D03*
Y206792D03*
X561024Y190256D03*
Y206792D03*
X704750Y126650D03*
G54D17*
G01X-84798Y-164972D02*
Y-244972D01*
G01D02*
X1172402D01*
G01X-88798Y-148972D02*
G02I-12000J0D01*
G01X-93948D02*
G02I-6850J0D01*
G01X-100798Y-164972D02*
Y-132972D01*
G01X-84798Y-148972D02*
X-116798D01*
G01X-84798Y-164972D02*
X1172402D01*
G01X-84798Y-200472D02*
X1172402D01*
G01X384902Y-164972D02*
Y-244972D01*
G01X522402Y-164972D02*
Y-244972D01*
G01X637402Y-164972D02*
Y-244972D01*
G01X804902Y-164972D02*
Y-244972D01*
G01X974902Y-164972D02*
Y-244972D01*
G01X1172402Y-164972D02*
Y-244972D01*
G01X1200402Y-148972D02*
G02I-12000J0D01*
G01X1195252D02*
G02I-6850J0D01*
G01X1188402Y-164972D02*
Y-132972D01*
G01X1204402Y-148972D02*
X1172402D01*
G54D18*
G01X-21653Y-58346D02*
G03X-6653Y-73346I15000J0D01*
G01X65080D02*
X-6653D01*
G01X9506Y0D02*
X69017D01*
G01X6722Y1153D02*
G03X9506Y0I2784J2784D01*
G01X1154Y6721D02*
X6722Y1153D01*
G01X1Y9505D02*
G03X1154Y6721I3937J0D01*
G01X1Y238051D02*
Y9505D01*
G01Y238051D02*
Y9505D01*
G01X-21653Y238051D02*
Y9505D01*
G01X1D02*
G03X1154Y6721I3937J0D01*
G01X-7873Y9505D02*
G03X-4414Y1153I11811J-1D01*
G01X1154Y6721D02*
X6722Y1153D01*
G01X-4414D02*
X1154Y-4415D01*
G01X6722Y1153D02*
G03X9506Y0I2784J2784D01*
G01X1154Y-4415D02*
G03X9506Y-7874I8351J8352D01*
G01Y0D02*
X69017D01*
G01X9506Y-7874D02*
X14917D01*
G01X-21653Y9505D02*
Y-58346D01*
G01X14917Y-7874D02*
G03Y0I0J3937D01*
G01X-7873Y50852D02*
Y9505D01*
G01Y81561D02*
G03X1I3937J-1D01*
G01Y50852D02*
G03X-7873I-3937J0D01*
G01Y186482D02*
Y81561D01*
G01X13443Y249862D02*
X611812D01*
G01X10659Y251015D02*
G03X13443Y249862I2784J2784D01*
G01X1154Y260520D02*
X10659Y251015D01*
G01X3938Y241988D02*
G03X1Y238051I0J-3937D01*
G01X602307Y241988D02*
X3938D01*
G01X602307D02*
X3938D01*
G01D02*
G03X1Y238051I0J-3937D01*
G01X-7873D02*
Y217191D01*
G01X1154Y260520D02*
X10659Y251015D01*
G01D02*
G03X13443Y249862I2784J2784D01*
G01D02*
X611812D01*
G01X-21653Y238051D02*
Y534327D01*
G01X-7873Y238051D02*
Y263304D01*
G01Y217191D02*
G03X1I3937J-1D01*
G01Y186482D02*
G03X-7873I-3937J0D01*
G01X1Y263304D02*
G03X1154Y260520I3937J0D01*
G01X1Y328602D02*
Y263304D01*
G01X3938Y332539D02*
G03X1Y328602I0J-3937D01*
G01X53151Y332539D02*
X3938D01*
G01X53151D02*
X3938D01*
G01D02*
G03X1Y328602I0J-3937D01*
G01X3938Y340413D02*
G03X-7873Y328602I0J-11811D01*
G01X1D02*
Y263304D01*
G01X-7873Y328602D02*
Y263304D01*
G01X1D02*
G03X1154Y260520I3937J0D01*
G01X10965Y332539D02*
G03Y340413I0J3937D01*
G01D02*
X3938D01*
G01X-6653Y565196D02*
G03X-21653Y550196I0J-15000D01*
G01X67796Y565196D02*
X-6653D01*
G01X-21653Y542201D02*
Y550196D01*
G01Y534327D02*
G03Y542201I0J3937D01*
G01X74922Y-73346D02*
X175828D01*
G01X72954Y-71378D02*
X74922Y-73346D01*
G01X72954Y-3937D02*
Y-71378D01*
G01X65080Y-7874D02*
Y-71772D01*
G01D02*
Y-73346D01*
G01X72954Y-3937D02*
G03X69017Y0I-3937J0D01*
G01X72954Y-3937D02*
G03X69017Y0I-3937J0D01*
G01X45626D02*
G03Y-7874I0J-3937D01*
G01D02*
X65080D01*
G01X51397Y241988D02*
G03Y249862I0J3937D01*
G01X93906D02*
G03Y241988I0J-3937D01*
G01X53151Y332539D02*
G03X57088Y336476I0J3937D01*
G01Y482345D02*
Y336476D01*
G01Y482345D02*
Y336476D01*
G01X53151Y332539D02*
G03X57088Y336476I0J3937D01*
G01X41674Y340413D02*
G03Y332539I0J-3937D01*
G01X49214Y340413D02*
X41674D01*
G01X49214Y442487D02*
Y340413D01*
G01X67796Y565196D02*
Y499724D01*
G01X75670Y563228D02*
Y495787D01*
G01X58241Y485129D02*
G03X57088Y482345I2784J-2784D01*
G01X63808Y490697D02*
X58241Y485129D01*
G01X66592Y491850D02*
G03X63808Y490697I0J-3937D01*
G01X71733Y491850D02*
X66592D01*
G01X71733D02*
G03X75670Y495787I0J3937D01*
G01X67796Y499724D02*
X66592D01*
G01Y491850D02*
G03X63808Y490697I0J-3937D01*
G01X66592Y499724D02*
G03X58240Y496265I-1J-11811D01*
G01X63808Y490697D02*
X58241Y485129D01*
G01X58240Y496264D02*
X52673Y490696D01*
G01X58241Y485129D02*
G03X57088Y482345I2784J-2784D01*
G01X52673Y490697D02*
G03X49214Y482343I8352J-8351D01*
G01Y482345D02*
Y473195D01*
G01X57088Y442487D02*
G03X49214I-3937J-1D01*
G01Y473195D02*
G03X57088I3937J0D01*
G01X77639Y565196D02*
X75670Y563228D01*
G01X173111Y565196D02*
X77639D01*
G01X177796Y-71378D02*
Y-52874D01*
G01X175828Y-73346D02*
X177796Y-71378D01*
G01X187245Y-52874D02*
G03X177796I-4725J0D01*
G01X175080Y563228D02*
X173111Y565196D01*
G01X175080Y534488D02*
Y563228D01*
G01Y534488D02*
G03X175867Y533700I787J-1D01*
G01X209529D02*
X175867D01*
G01X189214Y-73346D02*
X403466D01*
G01X187245Y-71378D02*
X189214Y-73346D01*
G01X187245Y-52874D02*
Y-71378D01*
G01X209529Y533700D02*
G03X210316Y534488I0J787D01*
G01Y563228D02*
Y534488D01*
G01X212284Y565196D02*
X210316Y563228D01*
G01X426536Y565196D02*
X212284D01*
G01X405434Y-71378D02*
Y-42638D01*
G01X403466Y-73346D02*
X405434Y-71378D01*
G01X406221Y-41850D02*
X439883D01*
G01X406221D02*
G03X405434Y-42638I1J-788D01*
G01X428505Y563228D02*
X426536Y565196D01*
G01X442639Y-73346D02*
X538111D01*
G01X440670Y-71378D02*
X442639Y-73346D01*
G01X440670Y-42638D02*
Y-71378D01*
G01Y-42638D02*
G03X439883Y-41850I-787J1D01*
G01X428504Y544723D02*
Y563227D01*
G01Y544723D02*
G03X437953I4724J0D01*
G01Y563227D02*
Y544723D01*
G01X428505Y544724D02*
Y563228D01*
G01Y544724D02*
G03X437954I4725J0D01*
G01Y563228D02*
Y544724D01*
G01X439922Y565196D02*
X437954Y563228D01*
G01X540828Y565196D02*
X439922D01*
G01X547954Y-73346D02*
X622403D01*
G01X547954D02*
Y-7874D01*
G01X540080Y-71378D02*
Y-3937D01*
G01X538111Y-73346D02*
X540080Y-71378D01*
G01X558662Y9505D02*
Y155374D01*
G01X557509Y6721D02*
G03X558662Y9505I-2784J2784D01*
G01X551942Y1153D02*
X557509Y6721D01*
G01X549158Y0D02*
G03X551942Y1153I0J3937D01*
G01X544017Y0D02*
X549158D01*
G01X544017D02*
G03X540080Y-3937I0J-3937D01*
G01X547954Y-7874D02*
X549158D01*
G01Y0D02*
G03X551942Y1153I0J3937D01*
G01X549158Y-7875D02*
G03X557510Y-4415I0J11811D01*
G01X551942Y1153D02*
X557509Y6721D01*
G01X557510Y-4414D02*
X563077Y1154D01*
G01X557509Y6721D02*
G03X558662Y9505I-2784J2784D01*
G01X563077Y1153D02*
G03X566536Y9507I-8352J8351D01*
G01X558662Y9505D02*
Y155374D01*
G01X566536Y9505D02*
Y18655D01*
G01D02*
G03X558662I-3937J-1D01*
G01Y49363D02*
G03X566536I3937J0D01*
G01D02*
Y151437D01*
G01X562599Y159311D02*
X611812D01*
G01X562599D02*
G03X558662Y155374I0J-3937D01*
G01X562599Y159311D02*
G03X558662Y155374I0J-3937D01*
G01X562599Y159311D02*
X611812D01*
G01X566536Y151437D02*
X574076D01*
G01D02*
G03Y159311I0J3937D01*
G01X564353Y249862D02*
G03Y241988I0J-3937D01*
G01X521844D02*
G03Y249862I0J3937D01*
G01X542796Y495787D02*
Y563228D01*
G01Y495787D02*
G03X546733Y491850I3937J0D01*
G01X606244D02*
X546733D01*
G01X606244D02*
X546733D01*
G01X542796Y495787D02*
G03X546733Y491850I3937J0D01*
G01X550670Y499724D02*
Y563622D01*
G01X570124Y491850D02*
G03Y499724I0J3937D01*
G01D02*
X550670D01*
G01Y565196D02*
X622403D01*
G01X542796Y563228D02*
X540828Y565196D01*
G01X550670Y563622D02*
Y565196D01*
G01X622403Y-73346D02*
G03X637403Y-58346I0J15000D01*
G01Y253799D02*
Y-58346D01*
G01X615749Y163248D02*
Y228546D01*
G01X611812Y159311D02*
G03X615749Y163248I0J3937D01*
G01X611812Y159311D02*
G03X615749Y163248I0J3937D01*
G01X611812Y151437D02*
G03X623623Y163248I0J11811D01*
G01X615749D02*
Y228546D01*
G01X623623Y163248D02*
Y228546D01*
G01X604785Y159311D02*
G03Y151437I0J-3937D01*
G01D02*
X611812D01*
G01X615749Y253799D02*
Y482345D01*
G01X611812Y249862D02*
G03X615749Y253799I0J3937D01*
G01X605091Y240835D02*
G03X602307Y241988I-2784J-2784D01*
G01X614596Y231330D02*
X605091Y240835D01*
G01X615749Y228546D02*
G03X614596Y231330I-3937J0D01*
G01X615749Y228546D02*
G03X614596Y231330I-3937J0D01*
G01D02*
X605091Y240835D01*
G01D02*
G03X602307Y241988I-2784J-2784D01*
G01X611812Y249862D02*
G03X615749Y253799I0J3937D01*
G01D02*
Y482345D01*
G01X623623Y253799D02*
Y274659D01*
G01X637403Y253799D02*
Y482345D01*
G01X623623Y228546D02*
Y253799D01*
G01Y274659D02*
G03X615749I-3937J0D01*
G01Y305368D02*
G03X623623I3937J0D01*
G01D02*
Y410289D01*
G01D02*
G03X615749I-3937J0D01*
G01X609028Y490697D02*
G03X606244Y491850I-2784J-2784D01*
G01X614596Y485129D02*
X609028Y490697D01*
G01X615749Y482345D02*
G03X614596Y485129I-3937J0D01*
G01X615749Y482345D02*
G03X614596Y485129I-3937J0D01*
G01X623623Y482345D02*
G03X620164Y490697I-11811J1D01*
G01X614596Y485129D02*
X609028Y490697D01*
G01X620164D02*
X614596Y496265D01*
G01X609028Y490697D02*
G03X606244Y491850I-2784J-2784D01*
G01X614596Y496265D02*
G03X606244Y499724I-8351J-8352D01*
G01D02*
X600833D01*
G01X637403Y482345D02*
Y550196D01*
G01X600833Y499724D02*
G03Y491850I0J-3937D01*
G01X615749Y440998D02*
G03X623623I3937J0D01*
G01D02*
Y482345D01*
G01X637403Y550196D02*
G03X622403Y565196I-15000J0D01*
G54D19*
G01X-65001Y-234972D02*
Y-217472D01*
X-60635D01*
X-58888Y-218347D01*
X-57578Y-219514D01*
X-56486Y-221263D01*
X-55613Y-223306D01*
X-55395Y-226222D01*
X-55613Y-229139D01*
X-56486Y-231181D01*
X-57578Y-232931D01*
X-58888Y-234097D01*
X-60635Y-234972D01*
X-65001D01*
G01X-48157Y-217472D02*
X-42698Y-234972D01*
X-37239Y-217472D01*
G01X-25198D02*
Y-234972D01*
G01X-30220Y-217472D02*
X-20176D01*
G01X5435Y-234972D02*
Y-217472D01*
X10894D01*
X12640Y-218347D01*
X13732Y-219514D01*
X14169Y-221847D01*
X13732Y-224181D01*
X12422Y-225639D01*
X10894Y-226514D01*
X5435D01*
G01X10894D02*
X14169Y-234972D01*
G01X27302Y-223306D02*
Y-234972D01*
G01Y-218639D02*
X26865Y-218347D01*
Y-217764D01*
X27302Y-217472D01*
X27739Y-217764D01*
Y-218347D01*
X27302Y-218639D01*
G01X41527Y-232931D02*
X42619Y-234097D01*
X44147Y-234972D01*
X45457D01*
X46767Y-234389D01*
X47640Y-233514D01*
X48077Y-232348D01*
X47859Y-230597D01*
X46985Y-229722D01*
X43055Y-227972D01*
X42182Y-225930D01*
X42619Y-224472D01*
X43492Y-223597D01*
X44802Y-223306D01*
X46112Y-223597D01*
X47422Y-224472D01*
G01X59027Y-227097D02*
X66014D01*
X65359Y-225055D01*
X64267Y-223889D01*
X62739Y-223306D01*
X61210Y-223597D01*
X59900Y-224472D01*
X59027Y-226514D01*
X58590Y-228264D01*
Y-230014D01*
X59027Y-231764D01*
X60119Y-233514D01*
X61429Y-234680D01*
X62957Y-234972D01*
X64485Y-234389D01*
X66014Y-232639D01*
G01X76745Y-234972D02*
Y-223306D01*
G01Y-225639D02*
X77837Y-224472D01*
X78929Y-223597D01*
X80457Y-223306D01*
X81548Y-223597D01*
X82859Y-224472D01*
G01X119605Y-218931D02*
X118295Y-218055D01*
X116767Y-217472D01*
X115020D01*
X113055Y-218347D01*
X111527Y-219805D01*
X110435Y-221556D01*
X109562Y-224472D01*
X109343Y-227097D01*
X109780Y-229722D01*
X110435Y-231472D01*
X111745Y-233222D01*
X113274Y-234389D01*
X114802Y-234972D01*
X116330D01*
X117859Y-234389D01*
X119169Y-233514D01*
X120261Y-232348D01*
G01X136232Y-234972D02*
Y-223306D01*
G01Y-225347D02*
X135359Y-224181D01*
X134048Y-223597D01*
X132520Y-223306D01*
X130992Y-223889D01*
X129682Y-225055D01*
X128808Y-226805D01*
X128372Y-229139D01*
X128808Y-231472D01*
X129682Y-233222D01*
X130992Y-234389D01*
X132520Y-234972D01*
X134048Y-234680D01*
X135359Y-233806D01*
X136232Y-232639D01*
G01X146745Y-234972D02*
Y-223306D01*
G01Y-225639D02*
X147837Y-224472D01*
X148929Y-223597D01*
X150457Y-223306D01*
X151548Y-223597D01*
X152859Y-224472D01*
G01X171232Y-217472D02*
Y-234972D01*
G01Y-232348D02*
X170359Y-233806D01*
X169048Y-234680D01*
X167520Y-234972D01*
X165774Y-234389D01*
X164464Y-232931D01*
X163590Y-231181D01*
X163372Y-229139D01*
X163590Y-227097D01*
X164464Y-225347D01*
X165774Y-223889D01*
X167520Y-223306D01*
X169048Y-223597D01*
X170140Y-224181D01*
X171232Y-225347D01*
G01X178252Y-240805D02*
X191352D01*
G01X197717Y-232639D02*
X199464Y-234097D01*
X201429Y-234972D01*
X203175D01*
X204922Y-234097D01*
X206232Y-232639D01*
X206887Y-230597D01*
X206450Y-228556D01*
X205359Y-226805D01*
X203394Y-225639D01*
X200774Y-225055D01*
X199245Y-223889D01*
X198590Y-221847D01*
X199027Y-219805D01*
X200119Y-218347D01*
X201647Y-217472D01*
X203175D01*
X204704Y-218055D01*
X206014Y-219514D01*
G01X215217Y-232639D02*
X216964Y-234097D01*
X218929Y-234972D01*
X220675D01*
X222422Y-234097D01*
X223732Y-232639D01*
X224387Y-230597D01*
X223950Y-228556D01*
X222859Y-226805D01*
X220894Y-225639D01*
X218274Y-225055D01*
X216745Y-223889D01*
X216090Y-221847D01*
X216527Y-219805D01*
X217619Y-218347D01*
X219147Y-217472D01*
X220675D01*
X222204Y-218055D01*
X223514Y-219514D01*
G01X250654Y-220389D02*
X251964Y-218639D01*
X253492Y-217764D01*
X255239Y-217472D01*
X257422Y-218055D01*
X258950Y-219514D01*
X259387Y-221263D01*
X259169Y-223014D01*
X258295Y-224472D01*
X253929Y-227389D01*
X251964Y-229430D01*
X250654Y-232348D01*
X250217Y-234972D01*
X259387D01*
G01X286527Y-232931D02*
X287619Y-234097D01*
X289147Y-234972D01*
X290457D01*
X291767Y-234389D01*
X292640Y-233514D01*
X293077Y-232348D01*
X292859Y-230597D01*
X291985Y-229722D01*
X288055Y-227972D01*
X287182Y-225930D01*
X287619Y-224472D01*
X288492Y-223597D01*
X289802Y-223306D01*
X291112Y-223597D01*
X292422Y-224472D01*
G01X307302Y-234972D02*
Y-217472D01*
G01X324802Y-234972D02*
X323492Y-234680D01*
X322182Y-233514D01*
X321308Y-231472D01*
X320872Y-229139D01*
X321308Y-226805D01*
X322182Y-224764D01*
X323492Y-223597D01*
X324802Y-223306D01*
X326112Y-223597D01*
X327422Y-224764D01*
X328295Y-226805D01*
X328514Y-229139D01*
X328295Y-231472D01*
X327422Y-233514D01*
X326112Y-234680D01*
X324802Y-234972D01*
G01X342302Y-217472D02*
Y-234972D01*
G01X339245Y-223306D02*
X345359D01*
G01X356527Y-232931D02*
X357619Y-234097D01*
X359147Y-234972D01*
X360457D01*
X361767Y-234389D01*
X362640Y-233514D01*
X363077Y-232348D01*
X362859Y-230597D01*
X361985Y-229722D01*
X358055Y-227972D01*
X357182Y-225930D01*
X357619Y-224472D01*
X358492Y-223597D01*
X359802Y-223306D01*
X361112Y-223597D01*
X362422Y-224472D01*
G01X109125Y-189972D02*
Y-172472D01*
X114802Y-187055D01*
X120479Y-172472D01*
Y-189972D01*
G01X132302D02*
X130992Y-189680D01*
X129682Y-188514D01*
X128808Y-186472D01*
X128372Y-184139D01*
X128808Y-181805D01*
X129682Y-179764D01*
X130992Y-178597D01*
X132302Y-178306D01*
X133612Y-178597D01*
X134922Y-179764D01*
X135795Y-181805D01*
X136014Y-184139D01*
X135795Y-186472D01*
X134922Y-188514D01*
X133612Y-189680D01*
X132302Y-189972D01*
G01X153732Y-172472D02*
Y-189972D01*
G01Y-187348D02*
X152859Y-188806D01*
X151548Y-189680D01*
X150020Y-189972D01*
X148274Y-189389D01*
X146964Y-187931D01*
X146090Y-186181D01*
X145872Y-184139D01*
X146090Y-182097D01*
X146964Y-180347D01*
X148274Y-178889D01*
X150020Y-178306D01*
X151548Y-178597D01*
X152640Y-179181D01*
X153732Y-180347D01*
G01X164027Y-182097D02*
X171014D01*
X170359Y-180055D01*
X169267Y-178889D01*
X167739Y-178306D01*
X166210Y-178597D01*
X164900Y-179472D01*
X164027Y-181514D01*
X163590Y-183264D01*
Y-185014D01*
X164027Y-186764D01*
X165119Y-188514D01*
X166429Y-189680D01*
X167957Y-189972D01*
X169485Y-189389D01*
X171014Y-187639D01*
G01X184802Y-189972D02*
Y-172472D01*
G01X418602Y-234972D02*
Y-217472D01*
X415982Y-220972D01*
G01Y-234972D02*
X421222D01*
G01X431299Y-232348D02*
X432608Y-233806D01*
X434137Y-234680D01*
X436102Y-234972D01*
X438067Y-234389D01*
X439595Y-233222D01*
X440687Y-231181D01*
X440905Y-228847D01*
X440469Y-226514D01*
X439377Y-225055D01*
X437848Y-223889D01*
X436320Y-223597D01*
X434792Y-223889D01*
X432827Y-225055D01*
X433482Y-217472D01*
X439377D01*
G01X449890Y-232931D02*
X451419Y-234389D01*
X453165Y-234972D01*
X454912Y-234389D01*
X456440Y-232639D01*
X457532Y-230014D01*
X457969Y-227389D01*
Y-224181D01*
X457532Y-221556D01*
X456440Y-219222D01*
X455130Y-218055D01*
X453602Y-217472D01*
X451855Y-218055D01*
X450545Y-219222D01*
X449672Y-220972D01*
X449235Y-223306D01*
X449672Y-225347D01*
X450764Y-227389D01*
X452074Y-228556D01*
X453602Y-228847D01*
X455348Y-228264D01*
X456659Y-226805D01*
X457969Y-224181D01*
G01X466954Y-227681D02*
X468482Y-225639D01*
X469792Y-224472D01*
X471539Y-223889D01*
X473067Y-224472D01*
X474159Y-225639D01*
X475032Y-227389D01*
X475250Y-229430D01*
X475032Y-231181D01*
X474159Y-232931D01*
X472848Y-234389D01*
X471320Y-234972D01*
X469574Y-234389D01*
X468045Y-232639D01*
X467172Y-230014D01*
X466954Y-227097D01*
X467390Y-223306D01*
X468045Y-221263D01*
X469137Y-219222D01*
X470665Y-217764D01*
X472194Y-217472D01*
X473722Y-218055D01*
X474814Y-219514D01*
G01X488602Y-234972D02*
X490130Y-234680D01*
X491877Y-233806D01*
X492969Y-232348D01*
X493405Y-230305D01*
X492969Y-228264D01*
X491659Y-226514D01*
X489694Y-225639D01*
X487510D01*
X486200Y-225055D01*
X485108Y-223597D01*
X484672Y-221556D01*
X485327Y-219514D01*
X486855Y-218055D01*
X488602Y-217472D01*
X490348Y-218055D01*
X491877Y-219514D01*
X492532Y-221556D01*
X492095Y-223597D01*
X491004Y-225055D01*
X489694Y-225639D01*
X487510D01*
X485545Y-226514D01*
X484235Y-228264D01*
X483799Y-230305D01*
X484235Y-232348D01*
X485327Y-233806D01*
X487074Y-234680D01*
X488602Y-234972D01*
G01X405485Y-189972D02*
Y-172472D01*
X410725D01*
X412472Y-173347D01*
X413782Y-175389D01*
X414219Y-177722D01*
X413782Y-180055D01*
X412690Y-181805D01*
X410725Y-182681D01*
X405485D01*
G01X432155Y-173931D02*
X430845Y-173055D01*
X429317Y-172472D01*
X427570D01*
X425605Y-173347D01*
X424077Y-174805D01*
X422985Y-176556D01*
X422112Y-179472D01*
X421893Y-182097D01*
X422330Y-184722D01*
X422985Y-186472D01*
X424295Y-188222D01*
X425824Y-189389D01*
X427352Y-189972D01*
X428880D01*
X430409Y-189389D01*
X431719Y-188514D01*
X432811Y-187348D01*
G01X446598Y-180639D02*
X447472Y-179764D01*
X448127Y-178306D01*
X448564Y-176263D01*
X448127Y-174514D01*
X447254Y-173347D01*
X445725Y-172472D01*
X439830D01*
Y-189972D01*
X447035D01*
X448564Y-188806D01*
X449437Y-187055D01*
X449874Y-185014D01*
X449437Y-182972D01*
X448127Y-181222D01*
X446598Y-180639D01*
X439830D01*
G01X455802Y-195805D02*
X468902D01*
G01X474830Y-189972D02*
Y-172472D01*
X484874Y-189972D01*
Y-172472D01*
G01X497352Y-189972D02*
X495605Y-189680D01*
X494077Y-188514D01*
X492767Y-186764D01*
X491893Y-184722D01*
X491457Y-182389D01*
Y-180055D01*
X491893Y-177722D01*
X492767Y-175680D01*
X494077Y-173931D01*
X495605Y-172764D01*
X497352Y-172472D01*
X499098Y-172764D01*
X500627Y-173931D01*
X501937Y-175680D01*
X502811Y-177722D01*
X503247Y-180055D01*
Y-182389D01*
X502811Y-184722D01*
X501937Y-186764D01*
X500627Y-188514D01*
X499098Y-189680D01*
X497352Y-189972D01*
G01X571152Y-234972D02*
Y-217472D01*
X568532Y-220972D01*
G01Y-234972D02*
X573772D01*
G01X583193D02*
X588652Y-217472D01*
X594111Y-234972D01*
G01X592145Y-228847D02*
X585158D01*
G01X548193Y-172472D02*
X553652Y-189972D01*
X559111Y-172472D01*
G01X575519Y-189972D02*
X566785D01*
Y-172472D01*
X575519D01*
G01X572025Y-180930D02*
X566785D01*
G01X584285Y-189972D02*
Y-172472D01*
X589744D01*
X591490Y-173347D01*
X592582Y-174514D01*
X593019Y-176847D01*
X592582Y-179181D01*
X591272Y-180639D01*
X589744Y-181514D01*
X584285D01*
G01X589744D02*
X593019Y-189972D01*
G01X606152Y-190555D02*
X605715Y-190264D01*
Y-189680D01*
X606152Y-189389D01*
X606589Y-189680D01*
Y-190264D01*
X606152Y-190555D01*
G01X660885Y-1700D02*
Y10800D01*
X668015Y-1700D01*
Y10800D01*
G01X676850Y-1700D02*
X675920Y-1492D01*
X674990Y-659D01*
X674370Y800D01*
X674060Y2467D01*
X674370Y4133D01*
X674990Y5592D01*
X675920Y6425D01*
X676850Y6633D01*
X677780Y6425D01*
X678710Y5592D01*
X679330Y4133D01*
X679485Y2467D01*
X679330Y800D01*
X678710Y-659D01*
X677780Y-1492D01*
X676850Y-1700D01*
G01X689250Y10800D02*
Y-1700D01*
G01X687080Y6633D02*
X691420D01*
G01X699325Y3925D02*
X704285D01*
X703820Y5383D01*
X703045Y6217D01*
X701960Y6633D01*
X700875Y6425D01*
X699945Y5800D01*
X699325Y4342D01*
X699015Y3091D01*
Y1842D01*
X699325Y592D01*
X700100Y-659D01*
X701030Y-1492D01*
X702115Y-1700D01*
X703200Y-1283D01*
X704285Y-34D01*
G01X714050Y-2117D02*
X713740Y-1908D01*
Y-1492D01*
X714050Y-1283D01*
X714360Y-1492D01*
Y-1908D01*
X714050Y-2117D01*
G01Y3508D02*
X713740Y3717D01*
Y4133D01*
X714050Y4342D01*
X714360Y4133D01*
Y3717D01*
X714050Y3508D01*
G01X723350Y-1700D02*
Y10800D01*
X727225D01*
X728465Y10175D01*
X729240Y9342D01*
X729550Y7675D01*
X729240Y6008D01*
X728310Y4967D01*
X727225Y4342D01*
X723350D01*
G01X727225D02*
X729550Y-1700D01*
G01X736525Y3925D02*
X741485D01*
X741020Y5383D01*
X740245Y6217D01*
X739160Y6633D01*
X738075Y6425D01*
X737145Y5800D01*
X736525Y4342D01*
X736215Y3091D01*
Y1842D01*
X736525Y592D01*
X737300Y-659D01*
X738230Y-1492D01*
X739315Y-1700D01*
X740400Y-1283D01*
X741485Y-34D01*
G01X750320Y-1700D02*
Y8925D01*
X750630Y9966D01*
X751250Y10592D01*
X752180Y10800D01*
X753110Y10383D01*
X753575Y9342D01*
G01X751715Y5800D02*
X748615D01*
G01X761325Y3925D02*
X766285D01*
X765820Y5383D01*
X765045Y6217D01*
X763960Y6633D01*
X762875Y6425D01*
X761945Y5800D01*
X761325Y4342D01*
X761015Y3091D01*
Y1842D01*
X761325Y592D01*
X762100Y-659D01*
X763030Y-1492D01*
X764115Y-1700D01*
X765200Y-1283D01*
X766285Y-34D01*
G01X773880Y-1700D02*
Y6633D01*
G01Y4967D02*
X774655Y5800D01*
X775430Y6425D01*
X776515Y6633D01*
X777290Y6425D01*
X778220Y5800D01*
G01X800850Y10800D02*
Y-1700D01*
G01X798680Y6633D02*
X803020D01*
G01X813250Y-1700D02*
X812320Y-1492D01*
X811390Y-659D01*
X810770Y800D01*
X810460Y2467D01*
X810770Y4133D01*
X811390Y5592D01*
X812320Y6425D01*
X813250Y6633D01*
X814180Y6425D01*
X815110Y5592D01*
X815730Y4133D01*
X815885Y2467D01*
X815730Y800D01*
X815110Y-659D01*
X814180Y-1492D01*
X813250Y-1700D01*
G01X834640D02*
Y10800D01*
X837740D01*
X838980Y10175D01*
X839910Y9342D01*
X840685Y8092D01*
X841305Y6633D01*
X841460Y4550D01*
X841305Y2467D01*
X840685Y1008D01*
X839910Y-242D01*
X838980Y-1075D01*
X837740Y-1700D01*
X834640D01*
G01X847350D02*
Y10800D01*
X851225D01*
X852465Y10175D01*
X853240Y9342D01*
X853550Y7675D01*
X853240Y6008D01*
X852310Y4967D01*
X851225Y4342D01*
X847350D01*
G01X851225D02*
X853550Y-1700D01*
G01X860990Y10800D02*
X864710D01*
G01X862850D02*
Y-1700D01*
G01X860990D02*
X864710D01*
G01X872150Y10800D02*
Y-1700D01*
X878350D01*
G01X884550Y10800D02*
Y-1700D01*
X890750D01*
G01X912450D02*
Y10800D01*
G01X927640Y-1700D02*
Y6633D01*
G01Y5175D02*
X927020Y6008D01*
X926090Y6425D01*
X925005Y6633D01*
X923920Y6217D01*
X922990Y5383D01*
X922370Y4133D01*
X922060Y2467D01*
X922370Y800D01*
X922990Y-450D01*
X923920Y-1283D01*
X925005Y-1700D01*
X926090Y-1492D01*
X927020Y-867D01*
X927640Y-34D01*
G01X933995Y-5450D02*
X934925Y-5867D01*
X936165Y-5450D01*
X936940Y-4617D01*
X937560Y-3575D01*
X938490Y-242D01*
X940505Y6633D01*
G01X935545D02*
X938490Y-242D01*
G01X947325Y3925D02*
X952285D01*
X951820Y5383D01*
X951045Y6217D01*
X949960Y6633D01*
X948875Y6425D01*
X947945Y5800D01*
X947325Y4342D01*
X947015Y3091D01*
Y1842D01*
X947325Y592D01*
X948100Y-659D01*
X949030Y-1492D01*
X950115Y-1700D01*
X951200Y-1283D01*
X952285Y-34D01*
G01X959880Y-1700D02*
Y6633D01*
G01Y4967D02*
X960655Y5800D01*
X961430Y6425D01*
X962515Y6633D01*
X963290Y6425D01*
X964220Y5800D01*
G01X985920Y-1700D02*
Y8925D01*
X986230Y9966D01*
X986850Y10592D01*
X987780Y10800D01*
X988710Y10383D01*
X989175Y9342D01*
G01X987315Y5800D02*
X984215D01*
G01X999250Y-1700D02*
X998320Y-1492D01*
X997390Y-659D01*
X996770Y800D01*
X996460Y2467D01*
X996770Y4133D01*
X997390Y5592D01*
X998320Y6425D01*
X999250Y6633D01*
X1000180Y6425D01*
X1001110Y5592D01*
X1001730Y4133D01*
X1001885Y2467D01*
X1001730Y800D01*
X1001110Y-659D01*
X1000180Y-1492D01*
X999250Y-1700D01*
G01X1009480D02*
Y6633D01*
G01Y4967D02*
X1010255Y5800D01*
X1011030Y6425D01*
X1012115Y6633D01*
X1012890Y6425D01*
X1013820Y5800D01*
G01X1039550Y-1700D02*
X1033350D01*
Y10800D01*
X1039550D01*
G01X1037070Y4758D02*
X1033350D01*
G01X1045750Y10800D02*
Y-1700D01*
X1051950D01*
G01X1058150Y10800D02*
Y-1700D01*
X1064350D01*
G01X1071790Y10800D02*
X1075510D01*
G01X1073650D02*
Y-1700D01*
G01X1071790D02*
X1075510D01*
G01X1082950D02*
Y10800D01*
X1086670D01*
X1087910Y10175D01*
X1088840Y8717D01*
X1089150Y7050D01*
X1088840Y5383D01*
X1088065Y4133D01*
X1086670Y3508D01*
X1082950D01*
G01X1095195Y-34D02*
X1096435Y-1075D01*
X1097830Y-1700D01*
X1099070D01*
X1100310Y-1075D01*
X1101240Y-34D01*
X1101705Y1425D01*
X1101395Y2883D01*
X1100620Y4133D01*
X1099225Y4967D01*
X1097365Y5383D01*
X1096280Y6217D01*
X1095815Y7675D01*
X1096125Y9133D01*
X1096900Y10175D01*
X1097985Y10800D01*
X1099070D01*
X1100155Y10383D01*
X1101085Y9342D01*
G01X1113950Y-1700D02*
X1107750D01*
Y10800D01*
X1113950D01*
G01X1111470Y4758D02*
X1107750D01*
G01X1138440Y10800D02*
Y-1700D01*
G01Y175D02*
X1137820Y-867D01*
X1136890Y-1492D01*
X1135805Y-1700D01*
X1134565Y-1283D01*
X1133635Y-242D01*
X1133015Y1008D01*
X1132860Y2467D01*
X1133015Y3925D01*
X1133635Y5175D01*
X1134565Y6217D01*
X1135805Y6633D01*
X1136890Y6425D01*
X1137665Y6008D01*
X1138440Y5175D01*
G01X1145880Y-1700D02*
Y6633D01*
G01Y4967D02*
X1146655Y5800D01*
X1147430Y6425D01*
X1148515Y6633D01*
X1149290Y6425D01*
X1150220Y5800D01*
G01X1160450Y6633D02*
Y-1700D01*
G01Y9966D02*
X1160140Y10175D01*
Y10592D01*
X1160450Y10800D01*
X1160760Y10592D01*
Y10175D01*
X1160450Y9966D01*
G01X1172850Y-1700D02*
Y10800D01*
G01X1185250Y-1700D02*
Y10800D01*
G01X1212840D02*
Y-1700D01*
G01Y175D02*
X1212220Y-867D01*
X1211290Y-1492D01*
X1210205Y-1700D01*
X1208965Y-1283D01*
X1208035Y-242D01*
X1207415Y1008D01*
X1207260Y2467D01*
X1207415Y3925D01*
X1208035Y5175D01*
X1208965Y6217D01*
X1210205Y6633D01*
X1211290Y6425D01*
X1212065Y6008D01*
X1212840Y5175D01*
G01X1222450Y6633D02*
Y-1700D01*
G01Y9966D02*
X1222140Y10175D01*
Y10592D01*
X1222450Y10800D01*
X1222760Y10592D01*
Y10175D01*
X1222450Y9966D01*
G01X1232680Y-1700D02*
Y6633D01*
G01Y4967D02*
X1233455Y5800D01*
X1234230Y6425D01*
X1235315Y6633D01*
X1236090Y6425D01*
X1237020Y5800D01*
G01X1244925Y3925D02*
X1249885D01*
X1249420Y5383D01*
X1248645Y6217D01*
X1247560Y6633D01*
X1246475Y6425D01*
X1245545Y5800D01*
X1244925Y4342D01*
X1244615Y3091D01*
Y1842D01*
X1244925Y592D01*
X1245700Y-659D01*
X1246630Y-1492D01*
X1247715Y-1700D01*
X1248800Y-1283D01*
X1249885Y-34D01*
G01X1262130Y5592D02*
X1261045Y6425D01*
X1260115Y6633D01*
X1258875Y6217D01*
X1257945Y5383D01*
X1257325Y3925D01*
X1257170Y2467D01*
X1257325Y1008D01*
X1257945Y-242D01*
X1258875Y-1283D01*
X1260115Y-1700D01*
X1261200Y-1283D01*
X1262130Y-450D01*
G01X1272050Y10800D02*
Y-1700D01*
G01X1269880Y6633D02*
X1274220D01*
G01X1284450D02*
Y-1700D01*
G01Y9966D02*
X1284140Y10175D01*
Y10592D01*
X1284450Y10800D01*
X1284760Y10592D01*
Y10175D01*
X1284450Y9966D01*
G01X1296850Y-1700D02*
X1295920Y-1492D01*
X1294990Y-659D01*
X1294370Y800D01*
X1294060Y2467D01*
X1294370Y4133D01*
X1294990Y5592D01*
X1295920Y6425D01*
X1296850Y6633D01*
X1297780Y6425D01*
X1298710Y5592D01*
X1299330Y4133D01*
X1299485Y2467D01*
X1299330Y800D01*
X1298710Y-659D01*
X1297780Y-1492D01*
X1296850Y-1700D01*
G01X1306615D02*
Y6633D01*
G01Y4550D02*
X1307235Y5592D01*
X1308165Y6425D01*
X1309405Y6633D01*
X1310490Y6425D01*
X1311420Y5592D01*
X1311885Y4133D01*
Y-1700D01*
G01X659800Y28300D02*
Y306200D01*
X1143400D01*
Y28300D01*
X659800D01*
G01Y84500D02*
X1143400D01*
G01X659800Y56400D02*
X1143400D01*
G01X659800Y168800D02*
X1143400D01*
G01X659800Y140700D02*
X1143400D01*
G01X659800Y112600D02*
X1143400D01*
G01X659800Y253100D02*
X1143400D01*
G01X659800Y225000D02*
X1143400D01*
G01X659800Y196900D02*
X1143400D01*
G01X659800Y281200D02*
X1143400D01*
G01X681299Y-234972D02*
Y-217472D01*
X685665D01*
X687412Y-218347D01*
X688722Y-219514D01*
X689814Y-221263D01*
X690687Y-223306D01*
X690905Y-226222D01*
X690687Y-229139D01*
X689814Y-231181D01*
X688722Y-232931D01*
X687412Y-234097D01*
X685665Y-234972D01*
X681299D01*
G01X699235D02*
Y-217472D01*
X704694D01*
X706440Y-218347D01*
X707532Y-219514D01*
X707969Y-221847D01*
X707532Y-224181D01*
X706222Y-225639D01*
X704694Y-226514D01*
X699235D01*
G01X704694D02*
X707969Y-234972D01*
G01X718482Y-217472D02*
X723722D01*
G01X721102D02*
Y-234972D01*
G01X718482D02*
X723722D01*
G01X734235Y-217472D02*
Y-234972D01*
X742969D01*
G01X751735Y-217472D02*
Y-234972D01*
X760469D01*
G01X681735Y-172472D02*
Y-189972D01*
X690469D01*
G01X707532D02*
Y-178306D01*
G01Y-180347D02*
X706659Y-179181D01*
X705348Y-178597D01*
X703820Y-178306D01*
X702292Y-178889D01*
X700982Y-180055D01*
X700108Y-181805D01*
X699672Y-184139D01*
X700108Y-186472D01*
X700982Y-188222D01*
X702292Y-189389D01*
X703820Y-189972D01*
X705348Y-189680D01*
X706659Y-188806D01*
X707532Y-187639D01*
G01X716517Y-195222D02*
X717827Y-195805D01*
X719574Y-195222D01*
X720665Y-194056D01*
X721539Y-192597D01*
X722848Y-187931D01*
X725687Y-178306D01*
G01X718700D02*
X722848Y-187931D01*
G01X735327Y-182097D02*
X742314D01*
X741659Y-180055D01*
X740567Y-178889D01*
X739039Y-178306D01*
X737510Y-178597D01*
X736200Y-179472D01*
X735327Y-181514D01*
X734890Y-183264D01*
Y-185014D01*
X735327Y-186764D01*
X736419Y-188514D01*
X737729Y-189680D01*
X739257Y-189972D01*
X740785Y-189389D01*
X742314Y-187639D01*
G01X753045Y-189972D02*
Y-178306D01*
G01Y-180639D02*
X754137Y-179472D01*
X755229Y-178597D01*
X756757Y-178306D01*
X757848Y-178597D01*
X759159Y-179472D01*
G01X670805Y234350D02*
Y246850D01*
X676695D01*
G01X674525Y240808D02*
X670805D01*
G01X684290Y246850D02*
X688010D01*
G01X686150D02*
Y234350D01*
G01X684290D02*
X688010D01*
G01X699480Y240600D02*
X702580D01*
Y236850D01*
X701650Y235600D01*
X700565Y234767D01*
X699015Y234350D01*
X697465Y234767D01*
X696380Y235600D01*
X695450Y236850D01*
X694830Y238308D01*
X694520Y239975D01*
Y241433D01*
X694830Y242683D01*
X695450Y244142D01*
X696380Y245392D01*
X697310Y246225D01*
X698550Y246850D01*
X699635D01*
X700875Y246433D01*
X701805Y245600D01*
G01X707540Y246850D02*
Y237892D01*
X708160Y236016D01*
X709400Y234767D01*
X710950Y234350D01*
X712500Y234767D01*
X713740Y236016D01*
X714360Y237892D01*
Y246850D01*
G01X720250Y234350D02*
Y246850D01*
X724125D01*
X725365Y246225D01*
X726140Y245392D01*
X726450Y243725D01*
X726140Y242058D01*
X725210Y241017D01*
X724125Y240392D01*
X720250D01*
G01X724125D02*
X726450Y234350D01*
G01X738850D02*
X732650D01*
Y246850D01*
X738850D01*
G01X736370Y240808D02*
X732650D01*
G01X743190Y287450D02*
Y299950D01*
X746290D01*
X747530Y299325D01*
X748460Y298492D01*
X749235Y297242D01*
X749855Y295783D01*
X750010Y293700D01*
X749855Y291617D01*
X749235Y290158D01*
X748460Y288908D01*
X747530Y288075D01*
X746290Y287450D01*
X743190D01*
G01X755900D02*
Y299950D01*
X759775D01*
X761015Y299325D01*
X761790Y298492D01*
X762100Y296825D01*
X761790Y295158D01*
X760860Y294117D01*
X759775Y293492D01*
X755900D01*
G01X759775D02*
X762100Y287450D01*
G01X769540Y299950D02*
X773260D01*
G01X771400D02*
Y287450D01*
G01X769540D02*
X773260D01*
G01X780700Y299950D02*
Y287450D01*
X786900D01*
G01X793100Y299950D02*
Y287450D01*
X799300D01*
G01X824410Y298908D02*
X823480Y299533D01*
X822395Y299950D01*
X821155D01*
X819760Y299325D01*
X818675Y298283D01*
X817900Y297033D01*
X817280Y294950D01*
X817125Y293075D01*
X817435Y291200D01*
X817900Y289950D01*
X818830Y288700D01*
X819915Y287867D01*
X821000Y287450D01*
X822085D01*
X823170Y287867D01*
X824100Y288491D01*
X824875Y289325D01*
G01X830145Y287450D02*
Y299950D01*
G01X836655D02*
Y287450D01*
G01Y293700D02*
X830145D01*
G01X841925Y287450D02*
X845800Y299950D01*
X849675Y287450D01*
G01X848280Y291825D02*
X843320D01*
G01X855100Y287450D02*
Y299950D01*
X858975D01*
X860215Y299325D01*
X860990Y298492D01*
X861300Y296825D01*
X860990Y295158D01*
X860060Y294117D01*
X858975Y293492D01*
X855100D01*
G01X858975D02*
X861300Y287450D01*
G01X870600Y299950D02*
Y287450D01*
G01X867035Y299950D02*
X874165D01*
G01X883000Y287033D02*
X882690Y287242D01*
Y287658D01*
X883000Y287867D01*
X883310Y287658D01*
Y287242D01*
X883000Y287033D01*
G01Y292658D02*
X882690Y292867D01*
Y293283D01*
X883000Y293492D01*
X883310Y293283D01*
Y292867D01*
X883000Y292658D01*
G01X907800Y299950D02*
Y287450D01*
G01X904235Y299950D02*
X911365D01*
G01X920200Y287450D02*
X918960Y287658D01*
X917875Y288491D01*
X916945Y289742D01*
X916325Y291200D01*
X916015Y292867D01*
Y294533D01*
X916325Y296200D01*
X916945Y297658D01*
X917875Y298908D01*
X918960Y299742D01*
X920200Y299950D01*
X921440Y299742D01*
X922525Y298908D01*
X923455Y297658D01*
X924075Y296200D01*
X924385Y294533D01*
Y292867D01*
X924075Y291200D01*
X923455Y289742D01*
X922525Y288491D01*
X921440Y287658D01*
X920200Y287450D01*
G01X929500D02*
Y299950D01*
X933220D01*
X934460Y299325D01*
X935390Y297867D01*
X935700Y296200D01*
X935390Y294533D01*
X934615Y293283D01*
X933220Y292658D01*
X929500D01*
G01X957400Y299950D02*
Y287450D01*
G01X955230Y295783D02*
X959570D01*
G01X969800Y287450D02*
X968870Y287658D01*
X967940Y288491D01*
X967320Y289950D01*
X967010Y291617D01*
X967320Y293283D01*
X967940Y294742D01*
X968870Y295575D01*
X969800Y295783D01*
X970730Y295575D01*
X971660Y294742D01*
X972280Y293283D01*
X972435Y291617D01*
X972280Y289950D01*
X971660Y288491D01*
X970730Y287658D01*
X969800Y287450D01*
G01X995840Y294117D02*
X996460Y294742D01*
X996925Y295783D01*
X997235Y297242D01*
X996925Y298492D01*
X996305Y299325D01*
X995220Y299950D01*
X991035D01*
Y287450D01*
X996150D01*
X997235Y288283D01*
X997855Y289533D01*
X998165Y290992D01*
X997855Y292450D01*
X996925Y293700D01*
X995840Y294117D01*
X991035D01*
G01X1007000Y287450D02*
X1005760Y287658D01*
X1004675Y288491D01*
X1003745Y289742D01*
X1003125Y291200D01*
X1002815Y292867D01*
Y294533D01*
X1003125Y296200D01*
X1003745Y297658D01*
X1004675Y298908D01*
X1005760Y299742D01*
X1007000Y299950D01*
X1008240Y299742D01*
X1009325Y298908D01*
X1010255Y297658D01*
X1010875Y296200D01*
X1011185Y294533D01*
Y292867D01*
X1010875Y291200D01*
X1010255Y289742D01*
X1009325Y288491D01*
X1008240Y287658D01*
X1007000Y287450D01*
G01X1019400Y299950D02*
Y287450D01*
G01X1015835Y299950D02*
X1022965D01*
G01X1031800D02*
Y287450D01*
G01X1028235Y299950D02*
X1035365D01*
G01X1044200Y287450D02*
X1042960Y287658D01*
X1041875Y288491D01*
X1040945Y289742D01*
X1040325Y291200D01*
X1040015Y292867D01*
Y294533D01*
X1040325Y296200D01*
X1040945Y297658D01*
X1041875Y298908D01*
X1042960Y299742D01*
X1044200Y299950D01*
X1045440Y299742D01*
X1046525Y298908D01*
X1047455Y297658D01*
X1048075Y296200D01*
X1048385Y294533D01*
Y292867D01*
X1048075Y291200D01*
X1047455Y289742D01*
X1046525Y288491D01*
X1045440Y287658D01*
X1044200Y287450D01*
G01X1052570D02*
Y299950D01*
X1056600Y289533D01*
X1060630Y299950D01*
Y287450D01*
G01X824705Y-218931D02*
X823395Y-218055D01*
X821867Y-217472D01*
X820120D01*
X818155Y-218347D01*
X816627Y-219805D01*
X815535Y-221556D01*
X814662Y-224472D01*
X814443Y-227097D01*
X814880Y-229722D01*
X815535Y-231472D01*
X816845Y-233222D01*
X818374Y-234389D01*
X819902Y-234972D01*
X821430D01*
X822959Y-234389D01*
X824269Y-233514D01*
X825361Y-232348D01*
G01X837402Y-234972D02*
X835655Y-234680D01*
X834127Y-233514D01*
X832817Y-231764D01*
X831943Y-229722D01*
X831507Y-227389D01*
Y-225055D01*
X831943Y-222722D01*
X832817Y-220680D01*
X834127Y-218931D01*
X835655Y-217764D01*
X837402Y-217472D01*
X839148Y-217764D01*
X840677Y-218931D01*
X841987Y-220680D01*
X842861Y-222722D01*
X843297Y-225055D01*
Y-227389D01*
X842861Y-229722D01*
X841987Y-231764D01*
X840677Y-233514D01*
X839148Y-234680D01*
X837402Y-234972D01*
G01X849880D02*
Y-217472D01*
X859924Y-234972D01*
Y-217472D01*
G01X867380Y-234972D02*
Y-217472D01*
X877424Y-234972D01*
Y-217472D01*
G01X887282D02*
X892522D01*
G01X889902D02*
Y-234972D01*
G01X887282D02*
X892522D01*
G01X911769D02*
X903035D01*
Y-217472D01*
X911769D01*
G01X908275Y-225930D02*
X903035D01*
G01X937817Y-234972D02*
X946987Y-217472D01*
G01X937817D02*
X946987Y-234972D01*
G01X955317D02*
Y-217472D01*
G01X964487D02*
Y-234972D01*
G01Y-226222D02*
X955317D01*
G01X823849Y-189972D02*
Y-172472D01*
X828215D01*
X829962Y-173347D01*
X831272Y-174514D01*
X832364Y-176263D01*
X833237Y-178306D01*
X833455Y-181222D01*
X833237Y-184139D01*
X832364Y-186181D01*
X831272Y-187931D01*
X829962Y-189097D01*
X828215Y-189972D01*
X823849D01*
G01X842877Y-182097D02*
X849864D01*
X849209Y-180055D01*
X848117Y-178889D01*
X846589Y-178306D01*
X845060Y-178597D01*
X843750Y-179472D01*
X842877Y-181514D01*
X842440Y-183264D01*
Y-185014D01*
X842877Y-186764D01*
X843969Y-188514D01*
X845279Y-189680D01*
X846807Y-189972D01*
X848335Y-189389D01*
X849864Y-187639D01*
G01X860377Y-187931D02*
X861469Y-189097D01*
X862997Y-189972D01*
X864307D01*
X865617Y-189389D01*
X866490Y-188514D01*
X866927Y-187348D01*
X866709Y-185597D01*
X865835Y-184722D01*
X861905Y-182972D01*
X861032Y-180930D01*
X861469Y-179472D01*
X862342Y-178597D01*
X863652Y-178306D01*
X864962Y-178597D01*
X866272Y-179472D01*
G01X881152Y-178306D02*
Y-189972D01*
G01Y-173639D02*
X880715Y-173347D01*
Y-172764D01*
X881152Y-172472D01*
X881589Y-172764D01*
Y-173347D01*
X881152Y-173639D01*
G01X895595Y-194347D02*
X897124Y-195514D01*
X898870Y-195805D01*
X900398Y-195514D01*
X901709Y-194056D01*
X902582Y-192014D01*
Y-178306D01*
G01Y-180639D02*
X901709Y-179472D01*
X900398Y-178597D01*
X898870Y-178306D01*
X897124Y-178889D01*
X896032Y-180055D01*
X895158Y-182097D01*
X894722Y-184139D01*
X894940Y-185889D01*
X895814Y-187931D01*
X897124Y-189389D01*
X898870Y-189972D01*
X900180Y-189680D01*
X901709Y-188514D01*
X902582Y-187348D01*
G01X912440Y-189972D02*
Y-178306D01*
G01Y-181222D02*
X913314Y-179764D01*
X914624Y-178597D01*
X916370Y-178306D01*
X917898Y-178597D01*
X919209Y-179764D01*
X919864Y-181805D01*
Y-189972D01*
G01X930377Y-182097D02*
X937364D01*
X936709Y-180055D01*
X935617Y-178889D01*
X934089Y-178306D01*
X932560Y-178597D01*
X931250Y-179472D01*
X930377Y-181514D01*
X929940Y-183264D01*
Y-185014D01*
X930377Y-186764D01*
X931469Y-188514D01*
X932779Y-189680D01*
X934307Y-189972D01*
X935835Y-189389D01*
X937364Y-187639D01*
G01X948095Y-189972D02*
Y-178306D01*
G01Y-180639D02*
X949187Y-179472D01*
X950279Y-178597D01*
X951807Y-178306D01*
X952898Y-178597D01*
X954209Y-179472D01*
G01X819450Y92300D02*
Y104800D01*
X817590Y102300D01*
G01Y92300D02*
X821310D01*
G01X828440Y94800D02*
X829370Y93341D01*
X830610Y92508D01*
X832005Y92300D01*
X833245Y92508D01*
X834485Y93550D01*
X835260Y94800D01*
X835415Y96050D01*
X835105Y97508D01*
X834020Y98550D01*
X832935Y98967D01*
X831540D01*
G01X832935D02*
X833865Y99592D01*
X834640Y100633D01*
X834950Y101883D01*
X834640Y103133D01*
X833865Y104175D01*
X832470Y104800D01*
X831075Y104592D01*
X829680Y103758D01*
G01X841615Y93758D02*
X842700Y92717D01*
X843940Y92300D01*
X845180Y92717D01*
X846265Y93966D01*
X847040Y95842D01*
X847350Y97717D01*
Y100008D01*
X847040Y101883D01*
X846265Y103550D01*
X845335Y104383D01*
X844250Y104800D01*
X843010Y104383D01*
X842080Y103550D01*
X841460Y102300D01*
X841150Y100633D01*
X841460Y99175D01*
X842235Y97717D01*
X843165Y96883D01*
X844250Y96675D01*
X845490Y97091D01*
X846420Y98133D01*
X847350Y100008D01*
G01X856650Y91883D02*
X856340Y92092D01*
Y92508D01*
X856650Y92717D01*
X856960Y92508D01*
Y92092D01*
X856650Y91883D01*
G01X869050Y104800D02*
X867810Y104383D01*
X866880Y103342D01*
X866260Y102092D01*
X865795Y100425D01*
X865640Y98550D01*
X865795Y96675D01*
X866260Y95008D01*
X866880Y93758D01*
X867810Y92717D01*
X869050Y92300D01*
X870290Y92717D01*
X871220Y93758D01*
X871840Y95008D01*
X872305Y96675D01*
X872460Y98550D01*
X872305Y100425D01*
X871840Y102092D01*
X871220Y103342D01*
X870290Y104383D01*
X869050Y104800D01*
G01X825650Y64200D02*
X826735Y64408D01*
X827975Y65033D01*
X828750Y66075D01*
X829060Y67533D01*
X828750Y68991D01*
X827820Y70242D01*
X826425Y70867D01*
X824875D01*
X823945Y71283D01*
X823170Y72325D01*
X822860Y73783D01*
X823325Y75242D01*
X824410Y76283D01*
X825650Y76700D01*
X826890Y76283D01*
X827975Y75242D01*
X828440Y73783D01*
X828130Y72325D01*
X827355Y71283D01*
X826425Y70867D01*
X824875D01*
X823480Y70242D01*
X822550Y68991D01*
X822240Y67533D01*
X822550Y66075D01*
X823325Y65033D01*
X824565Y64408D01*
X825650Y64200D01*
G01X835105Y69408D02*
X836190Y70867D01*
X837120Y71700D01*
X838360Y72117D01*
X839445Y71700D01*
X840220Y70867D01*
X840840Y69617D01*
X840995Y68158D01*
X840840Y66908D01*
X840220Y65658D01*
X839290Y64617D01*
X838205Y64200D01*
X836965Y64617D01*
X835880Y65866D01*
X835260Y67742D01*
X835105Y69825D01*
X835415Y72533D01*
X835880Y73992D01*
X836655Y75450D01*
X837740Y76492D01*
X838825Y76700D01*
X839910Y76283D01*
X840685Y75242D01*
G01X850450Y63783D02*
X850140Y63992D01*
Y64408D01*
X850450Y64617D01*
X850760Y64408D01*
Y63992D01*
X850450Y63783D01*
G01X862850Y76700D02*
X861610Y76283D01*
X860680Y75242D01*
X860060Y73992D01*
X859595Y72325D01*
X859440Y70450D01*
X859595Y68575D01*
X860060Y66908D01*
X860680Y65658D01*
X861610Y64617D01*
X862850Y64200D01*
X864090Y64617D01*
X865020Y65658D01*
X865640Y66908D01*
X866105Y68575D01*
X866260Y70450D01*
X866105Y72325D01*
X865640Y73992D01*
X865020Y75242D01*
X864090Y76283D01*
X862850Y76700D01*
G01X823015Y37558D02*
X824100Y36517D01*
X825340Y36100D01*
X826580Y36517D01*
X827665Y37766D01*
X828440Y39642D01*
X828750Y41517D01*
Y43808D01*
X828440Y45683D01*
X827665Y47350D01*
X826735Y48183D01*
X825650Y48600D01*
X824410Y48183D01*
X823480Y47350D01*
X822860Y46100D01*
X822550Y44433D01*
X822860Y42975D01*
X823635Y41517D01*
X824565Y40683D01*
X825650Y40475D01*
X826890Y40891D01*
X827820Y41933D01*
X828750Y43808D01*
G01X834640Y38600D02*
X835570Y37141D01*
X836810Y36308D01*
X838205Y36100D01*
X839445Y36308D01*
X840685Y37350D01*
X841460Y38600D01*
X841615Y39850D01*
X841305Y41308D01*
X840220Y42350D01*
X839135Y42767D01*
X837740D01*
G01X839135D02*
X840065Y43392D01*
X840840Y44433D01*
X841150Y45683D01*
X840840Y46933D01*
X840065Y47975D01*
X838670Y48600D01*
X837275Y48392D01*
X835880Y47558D01*
G01X850450Y35683D02*
X850140Y35892D01*
Y36308D01*
X850450Y36517D01*
X850760Y36308D01*
Y35892D01*
X850450Y35683D01*
G01X862850Y48600D02*
X861610Y48183D01*
X860680Y47142D01*
X860060Y45892D01*
X859595Y44225D01*
X859440Y42350D01*
X859595Y40475D01*
X860060Y38808D01*
X860680Y37558D01*
X861610Y36517D01*
X862850Y36100D01*
X864090Y36517D01*
X865020Y37558D01*
X865640Y38808D01*
X866105Y40475D01*
X866260Y42350D01*
X866105Y44225D01*
X865640Y45892D01*
X865020Y47142D01*
X864090Y48183D01*
X862850Y48600D01*
G01X749700Y253100D02*
Y28300D01*
G01X825650Y176600D02*
Y189100D01*
X823790Y186600D01*
G01Y176600D02*
X827510D01*
G01X835105Y187017D02*
X836035Y188266D01*
X837120Y188892D01*
X838360Y189100D01*
X839910Y188683D01*
X840995Y187642D01*
X841305Y186392D01*
X841150Y185141D01*
X840530Y184100D01*
X837430Y182017D01*
X836035Y180558D01*
X835105Y178475D01*
X834795Y176600D01*
X841305D01*
G01X850450Y176183D02*
X850140Y176392D01*
Y176808D01*
X850450Y177017D01*
X850760Y176808D01*
Y176392D01*
X850450Y176183D01*
G01X862850Y189100D02*
X861610Y188683D01*
X860680Y187642D01*
X860060Y186392D01*
X859595Y184725D01*
X859440Y182850D01*
X859595Y180975D01*
X860060Y179308D01*
X860680Y178058D01*
X861610Y177017D01*
X862850Y176600D01*
X864090Y177017D01*
X865020Y178058D01*
X865640Y179308D01*
X866105Y180975D01*
X866260Y182850D01*
X866105Y184725D01*
X865640Y186392D01*
X865020Y187642D01*
X864090Y188683D01*
X862850Y189100D01*
G01X822705Y158917D02*
X823635Y160166D01*
X824720Y160792D01*
X825960Y161000D01*
X827510Y160583D01*
X828595Y159542D01*
X828905Y158292D01*
X828750Y157041D01*
X828130Y156000D01*
X825030Y153917D01*
X823635Y152458D01*
X822705Y150375D01*
X822395Y148500D01*
X828905D01*
G01X838050D02*
X839135Y148708D01*
X840375Y149333D01*
X841150Y150375D01*
X841460Y151833D01*
X841150Y153291D01*
X840220Y154542D01*
X838825Y155167D01*
X837275D01*
X836345Y155583D01*
X835570Y156625D01*
X835260Y158083D01*
X835725Y159542D01*
X836810Y160583D01*
X838050Y161000D01*
X839290Y160583D01*
X840375Y159542D01*
X840840Y158083D01*
X840530Y156625D01*
X839755Y155583D01*
X838825Y155167D01*
X837275D01*
X835880Y154542D01*
X834950Y153291D01*
X834640Y151833D01*
X834950Y150375D01*
X835725Y149333D01*
X836965Y148708D01*
X838050Y148500D01*
G01X850450Y148083D02*
X850140Y148292D01*
Y148708D01*
X850450Y148917D01*
X850760Y148708D01*
Y148292D01*
X850450Y148083D01*
G01X862850Y161000D02*
X861610Y160583D01*
X860680Y159542D01*
X860060Y158292D01*
X859595Y156625D01*
X859440Y154750D01*
X859595Y152875D01*
X860060Y151208D01*
X860680Y149958D01*
X861610Y148917D01*
X862850Y148500D01*
X864090Y148917D01*
X865020Y149958D01*
X865640Y151208D01*
X866105Y152875D01*
X866260Y154750D01*
X866105Y156625D01*
X865640Y158292D01*
X865020Y159542D01*
X864090Y160583D01*
X862850Y161000D01*
G01X825340Y120400D02*
X825650Y123108D01*
X826115Y125400D01*
X826735Y127483D01*
X827510Y129775D01*
X828750Y132900D01*
X822550D01*
G01X838050Y120400D02*
Y132900D01*
X836190Y130400D01*
G01Y120400D02*
X839910D01*
G01X850450Y119983D02*
X850140Y120192D01*
Y120608D01*
X850450Y120817D01*
X850760Y120608D01*
Y120192D01*
X850450Y119983D01*
G01X862850Y132900D02*
X861610Y132483D01*
X860680Y131442D01*
X860060Y130192D01*
X859595Y128525D01*
X859440Y126650D01*
X859595Y124775D01*
X860060Y123108D01*
X860680Y121858D01*
X861610Y120817D01*
X862850Y120400D01*
X864090Y120817D01*
X865020Y121858D01*
X865640Y123108D01*
X866105Y124775D01*
X866260Y126650D01*
X866105Y128525D01*
X865640Y130192D01*
X865020Y131442D01*
X864090Y132483D01*
X862850Y132900D01*
G01X773725Y262450D02*
X777600Y274950D01*
X781475Y262450D01*
G01X780080Y266825D02*
X775120D01*
G01X786900Y274950D02*
Y262450D01*
X793100D01*
G01X799300Y274950D02*
Y262450D01*
X805500D01*
G01X823790Y274950D02*
Y265992D01*
X824410Y264116D01*
X825650Y262867D01*
X827200Y262450D01*
X828750Y262867D01*
X829990Y264116D01*
X830610Y265992D01*
Y274950D01*
G01X836035Y262450D02*
Y274950D01*
X843165Y262450D01*
Y274950D01*
G01X850140D02*
X853860D01*
G01X852000D02*
Y262450D01*
G01X850140D02*
X853860D01*
G01X864400Y274950D02*
Y262450D01*
G01X860835Y274950D02*
X867965D01*
G01X873545Y264116D02*
X874785Y263075D01*
X876180Y262450D01*
X877420D01*
X878660Y263075D01*
X879590Y264116D01*
X880055Y265575D01*
X879745Y267033D01*
X878970Y268283D01*
X877575Y269117D01*
X875715Y269533D01*
X874630Y270367D01*
X874165Y271825D01*
X874475Y273283D01*
X875250Y274325D01*
X876335Y274950D01*
X877420D01*
X878505Y274533D01*
X879435Y273492D01*
G01X897725Y262450D02*
X901600Y274950D01*
X905475Y262450D01*
G01X904080Y266825D02*
X899120D01*
G01X910900Y262450D02*
Y274950D01*
X914775D01*
X916015Y274325D01*
X916790Y273492D01*
X917100Y271825D01*
X916790Y270158D01*
X915860Y269117D01*
X914775Y268492D01*
X910900D01*
G01X914775D02*
X917100Y262450D01*
G01X929500D02*
X923300D01*
Y274950D01*
X929500D01*
G01X927020Y268908D02*
X923300D01*
G01X949340Y274950D02*
X953060D01*
G01X951200D02*
Y262450D01*
G01X949340D02*
X953060D01*
G01X960035D02*
Y274950D01*
X967165Y262450D01*
Y274950D01*
G01X984370Y262450D02*
Y274950D01*
X988400Y264533D01*
X992430Y274950D01*
Y262450D01*
G01X998940Y274950D02*
X1002660D01*
G01X1000800D02*
Y262450D01*
G01X998940D02*
X1002660D01*
G01X1010100Y274950D02*
Y262450D01*
X1016300D01*
G01X1022345Y264116D02*
X1023585Y263075D01*
X1024980Y262450D01*
X1026220D01*
X1027460Y263075D01*
X1028390Y264116D01*
X1028855Y265575D01*
X1028545Y267033D01*
X1027770Y268283D01*
X1026375Y269117D01*
X1024515Y269533D01*
X1023430Y270367D01*
X1022965Y271825D01*
X1023275Y273283D01*
X1024050Y274325D01*
X1025135Y274950D01*
X1026220D01*
X1027305Y274533D01*
X1028235Y273492D01*
G01X822395Y236016D02*
X823635Y234975D01*
X825030Y234350D01*
X826270D01*
X827510Y234975D01*
X828440Y236016D01*
X828905Y237475D01*
X828595Y238933D01*
X827820Y240183D01*
X826425Y241017D01*
X824565Y241433D01*
X823480Y242267D01*
X823015Y243725D01*
X823325Y245183D01*
X824100Y246225D01*
X825185Y246850D01*
X826270D01*
X827355Y246433D01*
X828285Y245392D01*
G01X836190Y246850D02*
X839910D01*
G01X838050D02*
Y234350D01*
G01X836190D02*
X839910D01*
G01X847505Y246850D02*
X853395D01*
X847505Y234350D01*
X853395D01*
G01X865950D02*
X859750D01*
Y246850D01*
X865950D01*
G01X863470Y240808D02*
X859750D01*
G01X825650Y204700D02*
Y217200D01*
X823790Y214700D01*
G01Y204700D02*
X827510D01*
G01X838050Y217200D02*
X836810Y216783D01*
X835880Y215742D01*
X835260Y214492D01*
X834795Y212825D01*
X834640Y210950D01*
X834795Y209075D01*
X835260Y207408D01*
X835880Y206158D01*
X836810Y205117D01*
X838050Y204700D01*
X839290Y205117D01*
X840220Y206158D01*
X840840Y207408D01*
X841305Y209075D01*
X841460Y210950D01*
X841305Y212825D01*
X840840Y214492D01*
X840220Y215742D01*
X839290Y216783D01*
X838050Y217200D01*
G01X850450Y204283D02*
X850140Y204492D01*
Y204908D01*
X850450Y205117D01*
X850760Y204908D01*
Y204492D01*
X850450Y204283D01*
G01X862850Y217200D02*
X861610Y216783D01*
X860680Y215742D01*
X860060Y214492D01*
X859595Y212825D01*
X859440Y210950D01*
X859595Y209075D01*
X860060Y207408D01*
X860680Y206158D01*
X861610Y205117D01*
X862850Y204700D01*
X864090Y205117D01*
X865020Y206158D01*
X865640Y207408D01*
X866105Y209075D01*
X866260Y210950D01*
X866105Y212825D01*
X865640Y214492D01*
X865020Y215742D01*
X864090Y216783D01*
X862850Y217200D01*
G01X968250Y92300D02*
Y104800D01*
X971970D01*
X973210Y104175D01*
X974140Y102717D01*
X974450Y101050D01*
X974140Y99383D01*
X973365Y98133D01*
X971970Y97508D01*
X968250D01*
G01X980650Y104800D02*
Y92300D01*
X986850D01*
G01X992275D02*
X996150Y104800D01*
X1000025Y92300D01*
G01X998630Y96675D02*
X993670D01*
G01X1008550Y104800D02*
Y92300D01*
G01X1004985Y104800D02*
X1012115D01*
G01X1024050Y92300D02*
X1017850D01*
Y104800D01*
X1024050D01*
G01X1021570Y98758D02*
X1017850D01*
G01X1029940Y92300D02*
Y104800D01*
X1033040D01*
X1034280Y104175D01*
X1035210Y103342D01*
X1035985Y102092D01*
X1036605Y100633D01*
X1036760Y98550D01*
X1036605Y96467D01*
X1035985Y95008D01*
X1035210Y93758D01*
X1034280Y92925D01*
X1033040Y92300D01*
X1029940D01*
G01X942985Y64200D02*
Y76700D01*
X950115Y64200D01*
Y76700D01*
G01X958950Y64200D02*
X957710Y64408D01*
X956625Y65241D01*
X955695Y66492D01*
X955075Y67950D01*
X954765Y69617D01*
Y71283D01*
X955075Y72950D01*
X955695Y74408D01*
X956625Y75658D01*
X957710Y76492D01*
X958950Y76700D01*
X960190Y76492D01*
X961275Y75658D01*
X962205Y74408D01*
X962825Y72950D01*
X963135Y71283D01*
Y69617D01*
X962825Y67950D01*
X962205Y66492D01*
X961275Y65241D01*
X960190Y64408D01*
X958950Y64200D01*
G01X967785D02*
Y76700D01*
X974915Y64200D01*
Y76700D01*
G01X981735Y68367D02*
X985765D01*
G01X993050Y64200D02*
Y76700D01*
X996770D01*
X998010Y76075D01*
X998940Y74617D01*
X999250Y72950D01*
X998940Y71283D01*
X998165Y70033D01*
X996770Y69408D01*
X993050D01*
G01X1005450Y76700D02*
Y64200D01*
X1011650D01*
G01X1017075D02*
X1020950Y76700D01*
X1024825Y64200D01*
G01X1023430Y68575D02*
X1018470D01*
G01X1033350Y76700D02*
Y64200D01*
G01X1029785Y76700D02*
X1036915D01*
G01X1048850Y64200D02*
X1042650D01*
Y76700D01*
X1048850D01*
G01X1046370Y70658D02*
X1042650D01*
G01X1054740Y64200D02*
Y76700D01*
X1057840D01*
X1059080Y76075D01*
X1060010Y75242D01*
X1060785Y73992D01*
X1061405Y72533D01*
X1061560Y70450D01*
X1061405Y68367D01*
X1060785Y66908D01*
X1060010Y65658D01*
X1059080Y64825D01*
X1057840Y64200D01*
X1054740D01*
G01X942985Y36100D02*
Y48600D01*
X950115Y36100D01*
Y48600D01*
G01X958950Y36100D02*
X957710Y36308D01*
X956625Y37141D01*
X955695Y38392D01*
X955075Y39850D01*
X954765Y41517D01*
Y43183D01*
X955075Y44850D01*
X955695Y46308D01*
X956625Y47558D01*
X957710Y48392D01*
X958950Y48600D01*
X960190Y48392D01*
X961275Y47558D01*
X962205Y46308D01*
X962825Y44850D01*
X963135Y43183D01*
Y41517D01*
X962825Y39850D01*
X962205Y38392D01*
X961275Y37141D01*
X960190Y36308D01*
X958950Y36100D01*
G01X967785D02*
Y48600D01*
X974915Y36100D01*
Y48600D01*
G01X981735Y40267D02*
X985765D01*
G01X993050Y36100D02*
Y48600D01*
X996770D01*
X998010Y47975D01*
X998940Y46517D01*
X999250Y44850D01*
X998940Y43183D01*
X998165Y41933D01*
X996770Y41308D01*
X993050D01*
G01X1005450Y48600D02*
Y36100D01*
X1011650D01*
G01X1017075D02*
X1020950Y48600D01*
X1024825Y36100D01*
G01X1023430Y40475D02*
X1018470D01*
G01X1033350Y48600D02*
Y36100D01*
G01X1029785Y48600D02*
X1036915D01*
G01X1048850Y36100D02*
X1042650D01*
Y48600D01*
X1048850D01*
G01X1046370Y42558D02*
X1042650D01*
G01X1054740Y36100D02*
Y48600D01*
X1057840D01*
X1059080Y47975D01*
X1060010Y47142D01*
X1060785Y45892D01*
X1061405Y44433D01*
X1061560Y42350D01*
X1061405Y40267D01*
X1060785Y38808D01*
X1060010Y37558D01*
X1059080Y36725D01*
X1057840Y36100D01*
X1054740D01*
G01X938800Y253100D02*
Y28300D01*
G01X968250Y176600D02*
Y189100D01*
X971970D01*
X973210Y188475D01*
X974140Y187017D01*
X974450Y185350D01*
X974140Y183683D01*
X973365Y182433D01*
X971970Y181808D01*
X968250D01*
G01X980650Y189100D02*
Y176600D01*
X986850D01*
G01X992275D02*
X996150Y189100D01*
X1000025Y176600D01*
G01X998630Y180975D02*
X993670D01*
G01X1008550Y189100D02*
Y176600D01*
G01X1004985Y189100D02*
X1012115D01*
G01X1024050Y176600D02*
X1017850D01*
Y189100D01*
X1024050D01*
G01X1021570Y183058D02*
X1017850D01*
G01X1029940Y176600D02*
Y189100D01*
X1033040D01*
X1034280Y188475D01*
X1035210Y187642D01*
X1035985Y186392D01*
X1036605Y184933D01*
X1036760Y182850D01*
X1036605Y180767D01*
X1035985Y179308D01*
X1035210Y178058D01*
X1034280Y177225D01*
X1033040Y176600D01*
X1029940D01*
G01X968250Y148500D02*
Y161000D01*
X971970D01*
X973210Y160375D01*
X974140Y158917D01*
X974450Y157250D01*
X974140Y155583D01*
X973365Y154333D01*
X971970Y153708D01*
X968250D01*
G01X980650Y161000D02*
Y148500D01*
X986850D01*
G01X992275D02*
X996150Y161000D01*
X1000025Y148500D01*
G01X998630Y152875D02*
X993670D01*
G01X1008550Y161000D02*
Y148500D01*
G01X1004985Y161000D02*
X1012115D01*
G01X1024050Y148500D02*
X1017850D01*
Y161000D01*
X1024050D01*
G01X1021570Y154958D02*
X1017850D01*
G01X1029940Y148500D02*
Y161000D01*
X1033040D01*
X1034280Y160375D01*
X1035210Y159542D01*
X1035985Y158292D01*
X1036605Y156833D01*
X1036760Y154750D01*
X1036605Y152667D01*
X1035985Y151208D01*
X1035210Y149958D01*
X1034280Y149125D01*
X1033040Y148500D01*
X1029940D01*
G01X968250Y120400D02*
Y132900D01*
X971970D01*
X973210Y132275D01*
X974140Y130817D01*
X974450Y129150D01*
X974140Y127483D01*
X973365Y126233D01*
X971970Y125608D01*
X968250D01*
G01X980650Y132900D02*
Y120400D01*
X986850D01*
G01X992275D02*
X996150Y132900D01*
X1000025Y120400D01*
G01X998630Y124775D02*
X993670D01*
G01X1008550Y132900D02*
Y120400D01*
G01X1004985Y132900D02*
X1012115D01*
G01X1024050Y120400D02*
X1017850D01*
Y132900D01*
X1024050D01*
G01X1021570Y126858D02*
X1017850D01*
G01X1029940Y120400D02*
Y132900D01*
X1033040D01*
X1034280Y132275D01*
X1035210Y131442D01*
X1035985Y130192D01*
X1036605Y128733D01*
X1036760Y126650D01*
X1036605Y124567D01*
X1035985Y123108D01*
X1035210Y121858D01*
X1034280Y121025D01*
X1033040Y120400D01*
X1029940D01*
G01X968250Y234350D02*
Y246850D01*
X971970D01*
X973210Y246225D01*
X974140Y244767D01*
X974450Y243100D01*
X974140Y241433D01*
X973365Y240183D01*
X971970Y239558D01*
X968250D01*
G01X980650Y246850D02*
Y234350D01*
X986850D01*
G01X992275D02*
X996150Y246850D01*
X1000025Y234350D01*
G01X998630Y238725D02*
X993670D01*
G01X1008550Y246850D02*
Y234350D01*
G01X1004985Y246850D02*
X1012115D01*
G01X1024050Y234350D02*
X1017850D01*
Y246850D01*
X1024050D01*
G01X1021570Y240808D02*
X1017850D01*
G01X1029940Y234350D02*
Y246850D01*
X1033040D01*
X1034280Y246225D01*
X1035210Y245392D01*
X1035985Y244142D01*
X1036605Y242683D01*
X1036760Y240600D01*
X1036605Y238517D01*
X1035985Y237058D01*
X1035210Y235808D01*
X1034280Y234975D01*
X1033040Y234350D01*
X1029940D01*
G01X968250Y204700D02*
Y217200D01*
X971970D01*
X973210Y216575D01*
X974140Y215117D01*
X974450Y213450D01*
X974140Y211783D01*
X973365Y210533D01*
X971970Y209908D01*
X968250D01*
G01X980650Y217200D02*
Y204700D01*
X986850D01*
G01X992275D02*
X996150Y217200D01*
X1000025Y204700D01*
G01X998630Y209075D02*
X993670D01*
G01X1008550Y217200D02*
Y204700D01*
G01X1004985Y217200D02*
X1012115D01*
G01X1024050Y204700D02*
X1017850D01*
Y217200D01*
X1024050D01*
G01X1021570Y211158D02*
X1017850D01*
G01X1029940Y204700D02*
Y217200D01*
X1033040D01*
X1034280Y216575D01*
X1035210Y215742D01*
X1035985Y214492D01*
X1036605Y213033D01*
X1036760Y210950D01*
X1036605Y208867D01*
X1035985Y207408D01*
X1035210Y206158D01*
X1034280Y205325D01*
X1033040Y204700D01*
X1029940D01*
G01X994852Y-217472D02*
X993105Y-218055D01*
X991795Y-219514D01*
X990922Y-221263D01*
X990267Y-223597D01*
X990049Y-226222D01*
X990267Y-228847D01*
X990922Y-231181D01*
X991795Y-232931D01*
X993105Y-234389D01*
X994852Y-234972D01*
X996598Y-234389D01*
X997909Y-232931D01*
X998782Y-231181D01*
X999437Y-228847D01*
X999655Y-226222D01*
X999437Y-223597D01*
X998782Y-221263D01*
X997909Y-219514D01*
X996598Y-218055D01*
X994852Y-217472D01*
G01X1012352Y-234972D02*
X1013880Y-234680D01*
X1015627Y-233806D01*
X1016719Y-232348D01*
X1017155Y-230305D01*
X1016719Y-228264D01*
X1015409Y-226514D01*
X1013444Y-225639D01*
X1011260D01*
X1009950Y-225055D01*
X1008858Y-223597D01*
X1008422Y-221556D01*
X1009077Y-219514D01*
X1010605Y-218055D01*
X1012352Y-217472D01*
X1014098Y-218055D01*
X1015627Y-219514D01*
X1016282Y-221556D01*
X1015845Y-223597D01*
X1014754Y-225055D01*
X1013444Y-225639D01*
X1011260D01*
X1009295Y-226514D01*
X1007985Y-228264D01*
X1007549Y-230305D01*
X1007985Y-232348D01*
X1009077Y-233806D01*
X1010824Y-234680D01*
X1012352Y-234972D01*
G01X1025922Y-235555D02*
X1033782Y-217472D01*
G01X1043204Y-220389D02*
X1044514Y-218639D01*
X1046042Y-217764D01*
X1047789Y-217472D01*
X1049972Y-218055D01*
X1051500Y-219514D01*
X1051937Y-221263D01*
X1051719Y-223014D01*
X1050845Y-224472D01*
X1046479Y-227389D01*
X1044514Y-229430D01*
X1043204Y-232348D01*
X1042767Y-234972D01*
X1051937D01*
G01X1060049Y-232348D02*
X1061358Y-233806D01*
X1062887Y-234680D01*
X1064852Y-234972D01*
X1066817Y-234389D01*
X1068345Y-233222D01*
X1069437Y-231181D01*
X1069655Y-228847D01*
X1069219Y-226514D01*
X1068127Y-225055D01*
X1066598Y-223889D01*
X1065070Y-223597D01*
X1063542Y-223889D01*
X1061577Y-225055D01*
X1062232Y-217472D01*
X1068127D01*
G01X1078422Y-235555D02*
X1086282Y-217472D01*
G01X1095704Y-220389D02*
X1097014Y-218639D01*
X1098542Y-217764D01*
X1100289Y-217472D01*
X1102472Y-218055D01*
X1104000Y-219514D01*
X1104437Y-221263D01*
X1104219Y-223014D01*
X1103345Y-224472D01*
X1098979Y-227389D01*
X1097014Y-229430D01*
X1095704Y-232348D01*
X1095267Y-234972D01*
X1104437D01*
G01X1117352Y-217472D02*
X1115605Y-218055D01*
X1114295Y-219514D01*
X1113422Y-221263D01*
X1112767Y-223597D01*
X1112549Y-226222D01*
X1112767Y-228847D01*
X1113422Y-231181D01*
X1114295Y-232931D01*
X1115605Y-234389D01*
X1117352Y-234972D01*
X1119098Y-234389D01*
X1120409Y-232931D01*
X1121282Y-231181D01*
X1121937Y-228847D01*
X1122155Y-226222D01*
X1121937Y-223597D01*
X1121282Y-221263D01*
X1120409Y-219514D01*
X1119098Y-218055D01*
X1117352Y-217472D01*
G01X1134852Y-234972D02*
Y-217472D01*
X1132232Y-220972D01*
G01Y-234972D02*
X1137472D01*
G01X1148204Y-227681D02*
X1149732Y-225639D01*
X1151042Y-224472D01*
X1152789Y-223889D01*
X1154317Y-224472D01*
X1155409Y-225639D01*
X1156282Y-227389D01*
X1156500Y-229430D01*
X1156282Y-231181D01*
X1155409Y-232931D01*
X1154098Y-234389D01*
X1152570Y-234972D01*
X1150824Y-234389D01*
X1149295Y-232639D01*
X1148422Y-230014D01*
X1148204Y-227097D01*
X1148640Y-223306D01*
X1149295Y-221263D01*
X1150387Y-219222D01*
X1151915Y-217764D01*
X1153444Y-217472D01*
X1154972Y-218055D01*
X1156064Y-219514D01*
G01X1042549Y-189972D02*
Y-172472D01*
X1046915D01*
X1048662Y-173347D01*
X1049972Y-174514D01*
X1051064Y-176263D01*
X1051937Y-178306D01*
X1052155Y-181222D01*
X1051937Y-184139D01*
X1051064Y-186181D01*
X1049972Y-187931D01*
X1048662Y-189097D01*
X1046915Y-189972D01*
X1042549D01*
G01X1068782D02*
Y-178306D01*
G01Y-180347D02*
X1067909Y-179181D01*
X1066598Y-178597D01*
X1065070Y-178306D01*
X1063542Y-178889D01*
X1062232Y-180055D01*
X1061358Y-181805D01*
X1060922Y-184139D01*
X1061358Y-186472D01*
X1062232Y-188222D01*
X1063542Y-189389D01*
X1065070Y-189972D01*
X1066598Y-189680D01*
X1067909Y-188806D01*
X1068782Y-187639D01*
G01X1082352Y-172472D02*
Y-189972D01*
G01X1079295Y-178306D02*
X1085409D01*
G01X1096577Y-182097D02*
X1103564D01*
X1102909Y-180055D01*
X1101817Y-178889D01*
X1100289Y-178306D01*
X1098760Y-178597D01*
X1097450Y-179472D01*
X1096577Y-181514D01*
X1096140Y-183264D01*
Y-185014D01*
X1096577Y-186764D01*
X1097669Y-188514D01*
X1098979Y-189680D01*
X1100507Y-189972D01*
X1102035Y-189389D01*
X1103564Y-187639D01*
G01X1065900Y253100D02*
Y28300D01*
G01X1101705Y102717D02*
X1102635Y103966D01*
X1103720Y104592D01*
X1104960Y104800D01*
X1106510Y104383D01*
X1107595Y103342D01*
X1107905Y102092D01*
X1107750Y100841D01*
X1107130Y99800D01*
X1104030Y97717D01*
X1102635Y96258D01*
X1101705Y94175D01*
X1101395Y92300D01*
X1107905D01*
G01X1101705Y69408D02*
X1102790Y70867D01*
X1103720Y71700D01*
X1104960Y72117D01*
X1106045Y71700D01*
X1106820Y70867D01*
X1107440Y69617D01*
X1107595Y68158D01*
X1107440Y66908D01*
X1106820Y65658D01*
X1105890Y64617D01*
X1104805Y64200D01*
X1103565Y64617D01*
X1102480Y65866D01*
X1101860Y67742D01*
X1101705Y69825D01*
X1102015Y72533D01*
X1102480Y73992D01*
X1103255Y75450D01*
X1104340Y76492D01*
X1105425Y76700D01*
X1106510Y76283D01*
X1107285Y75242D01*
G01X1106510Y36100D02*
Y48600D01*
X1100775Y39642D01*
X1108525D01*
G01X1092250Y176600D02*
Y189100D01*
X1090390Y186600D01*
G01Y176600D02*
X1094110D01*
G01X1101705Y181808D02*
X1102790Y183267D01*
X1103720Y184100D01*
X1104960Y184517D01*
X1106045Y184100D01*
X1106820Y183267D01*
X1107440Y182017D01*
X1107595Y180558D01*
X1107440Y179308D01*
X1106820Y178058D01*
X1105890Y177017D01*
X1104805Y176600D01*
X1103565Y177017D01*
X1102480Y178266D01*
X1101860Y180142D01*
X1101705Y182225D01*
X1102015Y184933D01*
X1102480Y186392D01*
X1103255Y187850D01*
X1104340Y188892D01*
X1105425Y189100D01*
X1106510Y188683D01*
X1107285Y187642D01*
G01X1118910Y176600D02*
Y189100D01*
X1113175Y180142D01*
X1120925D01*
G01X1088840Y151000D02*
X1089770Y149541D01*
X1091010Y148708D01*
X1092405Y148500D01*
X1093645Y148708D01*
X1094885Y149750D01*
X1095660Y151000D01*
X1095815Y152250D01*
X1095505Y153708D01*
X1094420Y154750D01*
X1093335Y155167D01*
X1091940D01*
G01X1093335D02*
X1094265Y155792D01*
X1095040Y156833D01*
X1095350Y158083D01*
X1095040Y159333D01*
X1094265Y160375D01*
X1092870Y161000D01*
X1091475Y160792D01*
X1090080Y159958D01*
G01X1101705Y158917D02*
X1102635Y160166D01*
X1103720Y160792D01*
X1104960Y161000D01*
X1106510Y160583D01*
X1107595Y159542D01*
X1107905Y158292D01*
X1107750Y157041D01*
X1107130Y156000D01*
X1104030Y153917D01*
X1102635Y152458D01*
X1101705Y150375D01*
X1101395Y148500D01*
X1107905D01*
G01X1117050D02*
X1118135Y148708D01*
X1119375Y149333D01*
X1120150Y150375D01*
X1120460Y151833D01*
X1120150Y153291D01*
X1119220Y154542D01*
X1117825Y155167D01*
X1116275D01*
X1115345Y155583D01*
X1114570Y156625D01*
X1114260Y158083D01*
X1114725Y159542D01*
X1115810Y160583D01*
X1117050Y161000D01*
X1118290Y160583D01*
X1119375Y159542D01*
X1119840Y158083D01*
X1119530Y156625D01*
X1118755Y155583D01*
X1117825Y155167D01*
X1116275D01*
X1114880Y154542D01*
X1113950Y153291D01*
X1113640Y151833D01*
X1113950Y150375D01*
X1114725Y149333D01*
X1115965Y148708D01*
X1117050Y148500D01*
G01X1106510Y120400D02*
Y132900D01*
X1100775Y123942D01*
X1108525D01*
G01X1092250Y234350D02*
X1091010Y234558D01*
X1089925Y235391D01*
X1088995Y236642D01*
X1088375Y238100D01*
X1088065Y239767D01*
Y241433D01*
X1088375Y243100D01*
X1088995Y244558D01*
X1089925Y245808D01*
X1091010Y246642D01*
X1092250Y246850D01*
X1093490Y246642D01*
X1094575Y245808D01*
X1095505Y244558D01*
X1096125Y243100D01*
X1096435Y241433D01*
Y239767D01*
X1096125Y238100D01*
X1095505Y236642D01*
X1094575Y235391D01*
X1093490Y234558D01*
X1092250Y234350D01*
G01X1093490Y237683D02*
X1095350Y234350D01*
G01X1104650Y246850D02*
Y234350D01*
G01X1101085Y246850D02*
X1108215D01*
G01X1117050Y234350D02*
Y239975D01*
X1113950Y246850D01*
G01X1120150D02*
X1117050Y239975D01*
G01X1088840Y206575D02*
X1089770Y205533D01*
X1090855Y204908D01*
X1092250Y204700D01*
X1093645Y205117D01*
X1094730Y205950D01*
X1095505Y207408D01*
X1095660Y209075D01*
X1095350Y210742D01*
X1094575Y211783D01*
X1093490Y212617D01*
X1092405Y212825D01*
X1091320Y212617D01*
X1089925Y211783D01*
X1090390Y217200D01*
X1094575D01*
G01X1104650D02*
X1103410Y216783D01*
X1102480Y215742D01*
X1101860Y214492D01*
X1101395Y212825D01*
X1101240Y210950D01*
X1101395Y209075D01*
X1101860Y207408D01*
X1102480Y206158D01*
X1103410Y205117D01*
X1104650Y204700D01*
X1105890Y205117D01*
X1106820Y206158D01*
X1107440Y207408D01*
X1107905Y209075D01*
X1108060Y210950D01*
X1107905Y212825D01*
X1107440Y214492D01*
X1106820Y215742D01*
X1105890Y216783D01*
X1104650Y217200D01*
G01X1114415Y206158D02*
X1115500Y205117D01*
X1116740Y204700D01*
X1117980Y205117D01*
X1119065Y206366D01*
X1119840Y208242D01*
X1120150Y210117D01*
Y212408D01*
X1119840Y214283D01*
X1119065Y215950D01*
X1118135Y216783D01*
X1117050Y217200D01*
X1115810Y216783D01*
X1114880Y215950D01*
X1114260Y214700D01*
X1113950Y213033D01*
X1114260Y211575D01*
X1115035Y210117D01*
X1115965Y209283D01*
X1117050Y209075D01*
X1118290Y209491D01*
X1119220Y210533D01*
X1120150Y212408D01*
M02*
